FILE_TYPE = MACRO_DRAWING;
SET COLOR_WIRE YELLOW;
SET COLOR_PROP MONO;
SET COLOR_DOT WHITE;
SET COLOR_ARC YELLOW;
SET COLOR_BODY GREEN;
SET COLOR_NOTE MONO;
SET PROP_DISPLAY VALUE;
SET PAGE_NUMBER P242;
FORCEADD GND..1
(-7750 1450);
FORCEPROP 3 LASTPIN (-7750 1500) SIG_NAME GND\g
J 0
(-7740 1510);
DISPLAY 0.659574 (-7740 1510);
PAINT MONO (-7740 1510);
DISPLAY INVISIBLE (-7740 1510);
FORCEPROP 1 LAST HDL_POWER GND
J 0
(-7750 1600);
DISPLAY 1.723404 (-7750 1600);
PAINT GREEN (-7750 1600);
DISPLAY INVISIBLE (-7750 1600);
FORCEPROP 1 LAST BODY_TYPE PLUMBING
J 0
(-7795 1407);
DISPLAY 0.340426 (-7795 1407);
PAINT GREEN (-7795 1407);
DISPLAY INVISIBLE (-7795 1407);
FORCEPROP 2 LAST CDS_LIB mstr_symbols
J 0
(-7750 1450);
PAINT MONO (-7750 1450);
DISPLAY INVISIBLE (-7750 1450);
FORCEPROP 1 LAST SIZE 1B
J 0
(-7675 1400);
DISPLAY 1.723404 (-7675 1400);
PAINT GREEN (-7675 1400);
DISPLAY INVISIBLE (-7675 1400);
FORCEPROP 2 LAST BOM_COST PROC_VRD_VCCIN_CPU0
J 0
(-8125 1525);
DISPLAY 1.446809 (-8125 1525);
PAINT MONO (-8125 1525);
DISPLAY INVISIBLE (-8125 1525);
FORCEPROP 2 LAST ROOM VDDQ_ABC_PWR_VR
J 0
(-8300 1525);
DISPLAY 1.936170 (-8300 1525);
PAINT ORANGE (-8300 1525);
DISPLAY INVISIBLE (-8300 1525);
FORCEPROP 1 LAST VOLTAGE 0
J 0
(-7750 1450);
PAINT SKYBLUE (-7750 1450);
DISPLAY INVISIBLE (-7750 1450);
FORCEPROP 1 LAST PATH I1
J 0
(-7675 1450);
DISPLAY 0.872340 (-7675 1450);
PAINT AQUA (-7675 1450);
DISPLAY INVISIBLE (-7675 1450);
FORCEADD GND..1
(-7750 3375);
FORCEPROP 3 LASTPIN (-7750 3425) SIG_NAME GND\g
J 0
(-7740 3435);
DISPLAY 0.659574 (-7740 3435);
PAINT MONO (-7740 3435);
DISPLAY INVISIBLE (-7740 3435);
FORCEPROP 1 LAST HDL_POWER GND
J 0
(-7750 3525);
DISPLAY 1.723404 (-7750 3525);
PAINT GREEN (-7750 3525);
DISPLAY INVISIBLE (-7750 3525);
FORCEPROP 1 LAST BODY_TYPE PLUMBING
J 0
(-7795 3332);
DISPLAY 0.340426 (-7795 3332);
PAINT GREEN (-7795 3332);
DISPLAY INVISIBLE (-7795 3332);
FORCEPROP 1 LAST PATH I10
J 0
(-7675 3375);
DISPLAY 0.872340 (-7675 3375);
PAINT AQUA (-7675 3375);
DISPLAY INVISIBLE (-7675 3375);
FORCEPROP 2 LAST CDS_LIB mstr_symbols
J 0
(-7750 3375);
PAINT MONO (-7750 3375);
DISPLAY INVISIBLE (-7750 3375);
FORCEPROP 1 LAST VOLTAGE 0
J 0
(-7750 3375);
PAINT SKYBLUE (-7750 3375);
DISPLAY INVISIBLE (-7750 3375);
FORCEPROP 2 LAST ROOM VDDQ_ABC_PWR_VR
J 0
(-8300 3450);
DISPLAY 1.936170 (-8300 3450);
PAINT ORANGE (-8300 3450);
DISPLAY INVISIBLE (-8300 3450);
FORCEPROP 2 LAST BOM_COST PROC_VRD_VCCIN_CPU0
J 0
(-8125 3450);
DISPLAY 1.446809 (-8125 3450);
PAINT MONO (-8125 3450);
DISPLAY INVISIBLE (-8125 3450);
FORCEPROP 1 LAST SIZE 1B
J 0
(-7675 3325);
DISPLAY 1.723404 (-7675 3325);
PAINT GREEN (-7675 3325);
DISPLAY INVISIBLE (-7675 3325);
FORCEADD PVDDQ_ABC..1
(-7750 4075);
FORCEPROP 3 LASTPIN (-7750 4025) SIG_NAME PVDDQ_ABC\g
J 0
(-7740 4035);
DISPLAY 0.659574 (-7740 4035);
PAINT MONO (-7740 4035);
DISPLAY INVISIBLE (-7740 4035);
FORCEPROP 1 LAST HDL_POWER PVDDQ_ABC
J 1
(-7750 4125);
DISPLAY 0.872340 (-7750 4125);
PAINT GREEN (-7750 4125);
DISPLAY INVISIBLE (-7750 4125);
FORCEPROP 1 LAST BODY_TYPE PLUMBING
J 0
(-7795 4032);
DISPLAY 0.340426 (-7795 4032);
PAINT GREEN (-7795 4032);
DISPLAY INVISIBLE (-7795 4032);
FORCEPROP 1 LAST PATH I26
J 0
(-7700 4100);
DISPLAY 0.872340 (-7700 4100);
PAINT AQUA (-7700 4100);
DISPLAY INVISIBLE (-7700 4100);
FORCEPROP 2 LAST CDS_LIB mstr_symbols
J 0
(-7750 4075);
PAINT MONO (-7750 4075);
DISPLAY INVISIBLE (-7750 4075);
FORCEPROP 1 LAST VOLTAGE 1.2V
J 0
(-7795 4032);
DISPLAY 0.340426 (-7795 4032);
PAINT GREEN (-7795 4032);
DISPLAY INVISIBLE (-7795 4032);
FORCEPROP 2 LAST BOM_COST PROC_SOCKET 
J 0
(-7750 4175);
DISPLAY 1.446809 (-7750 4175);
PAINT MONO (-7750 4175);
DISPLAY INVISIBLE (-7750 4175);
FORCEPROP 2 LAST ROOM VDDQ_ABC_PWR_VR
J 0
(-7750 4175);
DISPLAY 1.936170 (-7750 4175);
PAINT ORANGE (-7750 4175);
DISPLAY INVISIBLE (-7750 4175);
FORCEADD GND..1
(-3800 1450);
FORCEPROP 3 LASTPIN (-3800 1500) SIG_NAME GND\g
J 0
(-3790 1510);
DISPLAY 0.659574 (-3790 1510);
PAINT MONO (-3790 1510);
DISPLAY INVISIBLE (-3790 1510);
FORCEPROP 1 LAST HDL_POWER GND
J 0
(-3800 1600);
DISPLAY 1.723404 (-3800 1600);
PAINT GREEN (-3800 1600);
DISPLAY INVISIBLE (-3800 1600);
FORCEPROP 1 LAST BODY_TYPE PLUMBING
J 0
(-3845 1407);
DISPLAY 0.340426 (-3845 1407);
PAINT GREEN (-3845 1407);
DISPLAY INVISIBLE (-3845 1407);
FORCEPROP 2 LAST CDS_LIB mstr_symbols
J 0
(-3800 1450);
PAINT MONO (-3800 1450);
DISPLAY INVISIBLE (-3800 1450);
FORCEPROP 1 LAST VOLTAGE 0
J 0
(-3800 1450);
PAINT SKYBLUE (-3800 1450);
DISPLAY INVISIBLE (-3800 1450);
FORCEPROP 2 LAST ROOM VDDQ_ABC_PWR_VR
J 0
(-4350 1525);
DISPLAY 1.936170 (-4350 1525);
PAINT ORANGE (-4350 1525);
DISPLAY INVISIBLE (-4350 1525);
FORCEPROP 2 LAST BOM_COST PROC_VRD_VCCIN_CPU0
J 0
(-4175 1525);
DISPLAY 1.446809 (-4175 1525);
PAINT MONO (-4175 1525);
DISPLAY INVISIBLE (-4175 1525);
FORCEPROP 1 LAST SIZE 1B
J 0
(-3725 1400);
DISPLAY 1.723404 (-3725 1400);
PAINT GREEN (-3725 1400);
DISPLAY INVISIBLE (-3725 1400);
FORCEPROP 1 LAST PATH I27
J 0
(-3725 1450);
DISPLAY 0.872340 (-3725 1450);
PAINT AQUA (-3725 1450);
DISPLAY INVISIBLE (-3725 1450);
FORCEADD PVDDQ_DEF..1
(-3800 2150);
FORCEPROP 3 LASTPIN (-3800 2100) SIG_NAME PVDDQ_DEF\g
J 0
(-3790 2110);
DISPLAY 0.659574 (-3790 2110);
PAINT MONO (-3790 2110);
DISPLAY INVISIBLE (-3790 2110);
FORCEPROP 1 LAST HDL_POWER PVDDQ_DEF
J 1
(-3800 2200);
DISPLAY 0.872340 (-3800 2200);
PAINT GREEN (-3800 2200);
DISPLAY INVISIBLE (-3800 2200);
FORCEPROP 1 LAST BODY_TYPE PLUMBING
J 0
(-3845 2107);
DISPLAY 0.340426 (-3845 2107);
PAINT GREEN (-3845 2107);
DISPLAY INVISIBLE (-3845 2107);
FORCEPROP 1 LAST PATH I29
J 0
(-3750 2175);
DISPLAY 0.872340 (-3750 2175);
PAINT AQUA (-3750 2175);
DISPLAY INVISIBLE (-3750 2175);
FORCEPROP 1 LAST VOLTAGE 1.2V
J 0
(-3845 2107);
DISPLAY 0.340426 (-3845 2107);
PAINT GREEN (-3845 2107);
DISPLAY INVISIBLE (-3845 2107);
FORCEPROP 2 LAST BOM_COST PROC_SOCKET 
J 0
(-3800 2250);
DISPLAY 1.446809 (-3800 2250);
PAINT MONO (-3800 2250);
DISPLAY INVISIBLE (-3800 2250);
FORCEPROP 2 LAST ROOM VDDQ_DEF_PWR_VR
J 0
(-3800 2250);
DISPLAY 1.936170 (-3800 2250);
PAINT ORANGE (-3800 2250);
DISPLAY INVISIBLE (-3800 2250);
FORCEPROP 2 LAST CDS_LIB mstr_symbols
J 0
(-3800 2150);
PAINT MONO (-3800 2150);
DISPLAY INVISIBLE (-3800 2150);
FORCEADD PVDDQ_ABC..1
(-7750 2150);
FORCEPROP 3 LASTPIN (-7750 2100) SIG_NAME PVDDQ_ABC\g
J 0
(-7740 2110);
DISPLAY 0.659574 (-7740 2110);
PAINT MONO (-7740 2110);
DISPLAY INVISIBLE (-7740 2110);
FORCEPROP 1 LAST HDL_POWER PVDDQ_ABC
J 1
(-7750 2200);
DISPLAY 0.872340 (-7750 2200);
PAINT GREEN (-7750 2200);
DISPLAY INVISIBLE (-7750 2200);
FORCEPROP 1 LAST BODY_TYPE PLUMBING
J 0
(-7795 2107);
DISPLAY 0.340426 (-7795 2107);
PAINT GREEN (-7795 2107);
DISPLAY INVISIBLE (-7795 2107);
FORCEPROP 2 LAST CDS_LIB mstr_symbols
J 0
(-7750 2150);
PAINT MONO (-7750 2150);
DISPLAY INVISIBLE (-7750 2150);
FORCEPROP 2 LAST ROOM VDDQ_ABC_PWR_VR
J 0
(-7750 2250);
DISPLAY 1.936170 (-7750 2250);
PAINT ORANGE (-7750 2250);
DISPLAY INVISIBLE (-7750 2250);
FORCEPROP 2 LAST BOM_COST PROC_SOCKET 
J 0
(-7750 2250);
DISPLAY 1.446809 (-7750 2250);
PAINT MONO (-7750 2250);
DISPLAY INVISIBLE (-7750 2250);
FORCEPROP 1 LAST VOLTAGE 1.2V
J 0
(-7795 2107);
DISPLAY 0.340426 (-7795 2107);
PAINT GREEN (-7795 2107);
DISPLAY INVISIBLE (-7795 2107);
FORCEPROP 1 LAST PATH I3
J 0
(-7700 2175);
DISPLAY 0.872340 (-7700 2175);
PAINT AQUA (-7700 2175);
DISPLAY INVISIBLE (-7700 2175);
FORCEADD GND..1
(-3800 2400);
FORCEPROP 3 LASTPIN (-3800 2450) SIG_NAME GND\g
J 0
(-3790 2460);
DISPLAY 0.659574 (-3790 2460);
PAINT MONO (-3790 2460);
DISPLAY INVISIBLE (-3790 2460);
FORCEPROP 1 LAST HDL_POWER GND
J 0
(-3800 2550);
DISPLAY 1.723404 (-3800 2550);
PAINT GREEN (-3800 2550);
DISPLAY INVISIBLE (-3800 2550);
FORCEPROP 1 LAST BODY_TYPE PLUMBING
J 0
(-3845 2357);
DISPLAY 0.340426 (-3845 2357);
PAINT GREEN (-3845 2357);
DISPLAY INVISIBLE (-3845 2357);
FORCEPROP 1 LAST VOLTAGE 0
J 0
(-3800 2400);
PAINT SKYBLUE (-3800 2400);
DISPLAY INVISIBLE (-3800 2400);
FORCEPROP 2 LAST ROOM VDDQ_ABC_PWR_VR
J 0
(-4350 2475);
DISPLAY 1.936170 (-4350 2475);
PAINT ORANGE (-4350 2475);
DISPLAY INVISIBLE (-4350 2475);
FORCEPROP 2 LAST BOM_COST PROC_VRD_VCCIN_CPU0
J 0
(-4175 2475);
DISPLAY 1.446809 (-4175 2475);
PAINT MONO (-4175 2475);
DISPLAY INVISIBLE (-4175 2475);
FORCEPROP 1 LAST SIZE 1B
J 0
(-3725 2350);
DISPLAY 1.723404 (-3725 2350);
PAINT GREEN (-3725 2350);
DISPLAY INVISIBLE (-3725 2350);
FORCEPROP 2 LAST CDS_LIB mstr_symbols
J 0
(-3800 2400);
PAINT MONO (-3800 2400);
DISPLAY INVISIBLE (-3800 2400);
FORCEPROP 1 LAST PATH I33
J 0
(-3725 2400);
DISPLAY 0.872340 (-3725 2400);
PAINT AQUA (-3725 2400);
DISPLAY INVISIBLE (-3725 2400);
FORCEADD PVDDQ_DEF..1
(-3800 3100);
FORCEPROP 3 LASTPIN (-3800 3050) SIG_NAME PVDDQ_DEF\g
J 0
(-3790 3060);
DISPLAY 0.659574 (-3790 3060);
PAINT MONO (-3790 3060);
DISPLAY INVISIBLE (-3790 3060);
FORCEPROP 1 LAST HDL_POWER PVDDQ_DEF
J 1
(-3800 3150);
DISPLAY 0.872340 (-3800 3150);
PAINT GREEN (-3800 3150);
DISPLAY INVISIBLE (-3800 3150);
FORCEPROP 1 LAST BODY_TYPE PLUMBING
J 0
(-3845 3057);
DISPLAY 0.340426 (-3845 3057);
PAINT GREEN (-3845 3057);
DISPLAY INVISIBLE (-3845 3057);
FORCEPROP 2 LAST ROOM VDDQ_DEF_PWR_VR
J 0
(-3800 3200);
DISPLAY 1.936170 (-3800 3200);
PAINT ORANGE (-3800 3200);
DISPLAY INVISIBLE (-3800 3200);
FORCEPROP 2 LAST BOM_COST PROC_SOCKET 
J 0
(-3800 3200);
DISPLAY 1.446809 (-3800 3200);
PAINT MONO (-3800 3200);
DISPLAY INVISIBLE (-3800 3200);
FORCEPROP 1 LAST VOLTAGE 1.2V
J 0
(-3845 3057);
DISPLAY 0.340426 (-3845 3057);
PAINT GREEN (-3845 3057);
DISPLAY INVISIBLE (-3845 3057);
FORCEPROP 2 LAST CDS_LIB mstr_symbols
J 0
(-3800 3100);
PAINT MONO (-3800 3100);
DISPLAY INVISIBLE (-3800 3100);
FORCEPROP 1 LAST PATH I35
J 0
(-3750 3125);
DISPLAY 0.872340 (-3750 3125);
PAINT AQUA (-3750 3125);
DISPLAY INVISIBLE (-3750 3125);
FORCEADD GND..1
(-3800 3350);
FORCEPROP 3 LASTPIN (-3800 3400) SIG_NAME GND\g
J 0
(-3790 3410);
DISPLAY 0.659574 (-3790 3410);
PAINT MONO (-3790 3410);
DISPLAY INVISIBLE (-3790 3410);
FORCEPROP 1 LAST HDL_POWER GND
J 0
(-3800 3500);
DISPLAY 1.723404 (-3800 3500);
PAINT GREEN (-3800 3500);
DISPLAY INVISIBLE (-3800 3500);
FORCEPROP 1 LAST BODY_TYPE PLUMBING
J 0
(-3845 3307);
DISPLAY 0.340426 (-3845 3307);
PAINT GREEN (-3845 3307);
DISPLAY INVISIBLE (-3845 3307);
FORCEPROP 1 LAST VOLTAGE 0
J 0
(-3800 3350);
PAINT SKYBLUE (-3800 3350);
DISPLAY INVISIBLE (-3800 3350);
FORCEPROP 2 LAST ROOM VDDQ_ABC_PWR_VR
J 0
(-4350 3425);
DISPLAY 1.936170 (-4350 3425);
PAINT ORANGE (-4350 3425);
DISPLAY INVISIBLE (-4350 3425);
FORCEPROP 2 LAST BOM_COST PROC_VRD_VCCIN_CPU0
J 0
(-4175 3425);
DISPLAY 1.446809 (-4175 3425);
PAINT MONO (-4175 3425);
DISPLAY INVISIBLE (-4175 3425);
FORCEPROP 1 LAST SIZE 1B
J 0
(-3725 3300);
DISPLAY 1.723404 (-3725 3300);
PAINT GREEN (-3725 3300);
DISPLAY INVISIBLE (-3725 3300);
FORCEPROP 2 LAST CDS_LIB mstr_symbols
J 0
(-3800 3350);
PAINT MONO (-3800 3350);
DISPLAY INVISIBLE (-3800 3350);
FORCEPROP 1 LAST PATH I36
J 0
(-3725 3350);
DISPLAY 0.872340 (-3725 3350);
PAINT AQUA (-3725 3350);
DISPLAY INVISIBLE (-3725 3350);
FORCEADD PVDDQ_DEF..1
(-3800 4050);
FORCEPROP 3 LASTPIN (-3800 4000) SIG_NAME PVDDQ_DEF\g
J 0
(-3790 4010);
DISPLAY 0.659574 (-3790 4010);
PAINT MONO (-3790 4010);
DISPLAY INVISIBLE (-3790 4010);
FORCEPROP 1 LAST HDL_POWER PVDDQ_DEF
J 1
(-3800 4100);
DISPLAY 0.872340 (-3800 4100);
PAINT GREEN (-3800 4100);
DISPLAY INVISIBLE (-3800 4100);
FORCEPROP 1 LAST BODY_TYPE PLUMBING
J 0
(-3845 4007);
DISPLAY 0.340426 (-3845 4007);
PAINT GREEN (-3845 4007);
DISPLAY INVISIBLE (-3845 4007);
FORCEPROP 2 LAST ROOM VDDQ_DEF_PWR_VR
J 0
(-3800 4150);
DISPLAY 1.936170 (-3800 4150);
PAINT ORANGE (-3800 4150);
DISPLAY INVISIBLE (-3800 4150);
FORCEPROP 2 LAST BOM_COST PROC_SOCKET 
J 0
(-3800 4150);
DISPLAY 1.446809 (-3800 4150);
PAINT MONO (-3800 4150);
DISPLAY INVISIBLE (-3800 4150);
FORCEPROP 1 LAST VOLTAGE 1.2V
J 0
(-3845 4007);
DISPLAY 0.340426 (-3845 4007);
PAINT GREEN (-3845 4007);
DISPLAY INVISIBLE (-3845 4007);
FORCEPROP 2 LAST CDS_LIB mstr_symbols
J 0
(-3800 4050);
PAINT MONO (-3800 4050);
DISPLAY INVISIBLE (-3800 4050);
FORCEPROP 1 LAST PATH I50
J 0
(-3750 4075);
DISPLAY 0.872340 (-3750 4075);
PAINT AQUA (-3750 4075);
DISPLAY INVISIBLE (-3750 4075);
FORCEADD CAP_A..1
(-7750 2800);
FORCEPROP 1 LAST LOCATION C5G41
J 0
(-7700 2900);
DISPLAY 0.617021 (-7700 2900);
PAINT AQUA (-7700 2900);
FORCEPROP 1 LAST TOLERANCE 20%
J 0
(-7700 2750);
DISPLAY 0.617021 (-7700 2750);
PAINT SKYBLUE (-7700 2750);
FORCEPROP 1 LAST MATERIAL X6S
J 0
(-7700 2700);
DISPLAY 0.617021 (-7700 2700);
PAINT SKYBLUE (-7700 2700);
FORCEPROP 1 LAST PACK_TYPE 0603V
J 0
(-7700 2600);
DISPLAY 0.617021 (-7700 2600);
PAINT SKYBLUE (-7700 2600);
FORCEPROP 1 LASTPIN (-7750 2900) $PN 1
J 0
(-7740 2880);
DISPLAY 0.787234 (-7740 2880);
PAINT ORANGE (-7740 2880);
FORCEPROP 1 LASTPIN (-7750 2700) $PN 2
J 0
(-7740 2680);
DISPLAY 0.787234 (-7740 2680);
PAINT ORANGE (-7740 2680);
FORCEPROP 1 LAST VOLTAGE 4V
J 0
(-7700 2800);
DISPLAY 0.617021 (-7700 2800);
PAINT SKYBLUE (-7700 2800);
FORCEPROP 1 LAST VALUE 22.0UF
J 0
(-7700 2850);
DISPLAY 0.617021 (-7700 2850);
PAINT SKYBLUE (-7700 2850);
FORCEPROP 0 LAST GROUP PWR_MLCC_CAP
J 0
(-7701 2520);
DISPLAY 0.638298 (-7701 2520);
PAINT BROWN (-7701 2520);
DISPLAY BOTH (-7701 2520);
FORCEPROP 1 LAST PART_NUMBER E15431-004
J 0
(-7700 2650);
DISPLAY 0.617021 (-7700 2650);
PAINT BLUE (-7700 2650);
FORCEPROP 0 LAST BOM_DS NOPOP
J 0
(-7694 2552);
DISPLAY 0.638298 (-7694 2552);
PAINT BROWN (-7694 2552);
DISPLAY BOTH (-7694 2552);
FORCEPROP 2 LAST SEC_TYPE 0603V
J 0
(-7700 3000);
DISPLAY 1.021277 (-7700 3000);
PAINT ORANGE (-7700 3000);
DISPLAY INVISIBLE (-7700 3000);
FORCEPROP 0 LAST SEC 1
J 0
(-7700 2950);
DISPLAY 0.680851 (-7700 2950);
PAINT MONO (-7700 2950);
DISPLAY INVISIBLE (-7700 2950);
FORCEPROP 2 LAST CDS_LIB dev_discrete
J 0
(-7750 2800);
PAINT MONO (-7750 2800);
DISPLAY INVISIBLE (-7750 2800);
FORCEPROP 1 LAST PATH I53
J 0
(-7700 2950);
DISPLAY 0.978723 (-7700 2950);
PAINT WHITE (-7700 2950);
DISPLAY INVISIBLE (-7700 2950);
FORCEPROP 0 LAST ROOM PVDDQ_KLM
J 0
(-7700 3000);
DISPLAY 1.021277 (-7700 3000);
PAINT ORANGE (-7700 3000);
DISPLAY INVISIBLE (-7700 3000);
FORCEADD CAP_A..1
(-7350 2800);
FORCEPROP 0 LAST GROUP PWR_MLCC_CAP
J 0
(-7290 2465);
DISPLAY 0.638298 (-7290 2465);
PAINT BROWN (-7290 2465);
DISPLAY BOTH (-7290 2465);
FORCEPROP 1 LAST PART_NUMBER E15431-004
J 0
(-7300 2650);
DISPLAY 0.617021 (-7300 2650);
PAINT BLUE (-7300 2650);
FORCEPROP 1 LAST LOCATION C5G42
J 0
(-7300 2900);
DISPLAY 0.617021 (-7300 2900);
PAINT AQUA (-7300 2900);
FORCEPROP 1 LAST TOLERANCE 20%
J 0
(-7300 2750);
DISPLAY 0.617021 (-7300 2750);
PAINT SKYBLUE (-7300 2750);
FORCEPROP 1 LAST VALUE 22.0UF
J 0
(-7300 2850);
DISPLAY 0.617021 (-7300 2850);
PAINT SKYBLUE (-7300 2850);
FORCEPROP 1 LAST VOLTAGE 4V
J 0
(-7300 2800);
DISPLAY 0.617021 (-7300 2800);
PAINT SKYBLUE (-7300 2800);
FORCEPROP 1 LAST PACK_TYPE 0603V
J 0
(-7300 2600);
DISPLAY 0.617021 (-7300 2600);
PAINT SKYBLUE (-7300 2600);
FORCEPROP 1 LASTPIN (-7350 2700) $PN 2
J 0
(-7340 2680);
DISPLAY 0.787234 (-7340 2680);
PAINT ORANGE (-7340 2680);
FORCEPROP 1 LASTPIN (-7350 2900) $PN 1
J 0
(-7340 2880);
DISPLAY 0.787234 (-7340 2880);
PAINT ORANGE (-7340 2880);
FORCEPROP 1 LAST MATERIAL X6S
J 0
(-7300 2700);
DISPLAY 0.617021 (-7300 2700);
PAINT SKYBLUE (-7300 2700);
FORCEPROP 0 LAST BOM_DS NOPOP
J 0
(-7294 2552);
DISPLAY 0.638298 (-7294 2552);
PAINT BROWN (-7294 2552);
DISPLAY BOTH (-7294 2552);
FORCEPROP 0 LAST ROOM PVDDQ_KLM
J 0
(-7300 3000);
DISPLAY 1.021277 (-7300 3000);
PAINT ORANGE (-7300 3000);
DISPLAY INVISIBLE (-7300 3000);
FORCEPROP 1 LAST PATH I54
J 0
(-7300 2950);
DISPLAY 0.978723 (-7300 2950);
PAINT WHITE (-7300 2950);
DISPLAY INVISIBLE (-7300 2950);
FORCEPROP 2 LAST CDS_LIB dev_discrete
J 0
(-7350 2800);
PAINT MONO (-7350 2800);
DISPLAY INVISIBLE (-7350 2800);
FORCEPROP 0 LAST SEC 1
J 0
(-7300 2950);
DISPLAY 0.680851 (-7300 2950);
PAINT MONO (-7300 2950);
DISPLAY INVISIBLE (-7300 2950);
FORCEPROP 2 LAST SEC_TYPE 0603V
J 0
(-7300 3000);
DISPLAY 1.021277 (-7300 3000);
PAINT ORANGE (-7300 3000);
DISPLAY INVISIBLE (-7300 3000);
FORCEADD CAP_A..1
(-6550 2800);
FORCEPROP 0 LAST GROUP PWR_MLCC_CAP
J 0
(-6509 2448);
DISPLAY 0.638298 (-6509 2448);
PAINT BROWN (-6509 2448);
DISPLAY BOTH (-6509 2448);
FORCEPROP 1 LAST VALUE 22.0UF
J 0
(-6500 2850);
DISPLAY 0.617021 (-6500 2850);
PAINT SKYBLUE (-6500 2850);
FORCEPROP 1 LAST MATERIAL X6S
J 0
(-6500 2700);
DISPLAY 0.617021 (-6500 2700);
PAINT SKYBLUE (-6500 2700);
FORCEPROP 1 LAST LOCATION C5G44
J 0
(-6500 2900);
DISPLAY 0.617021 (-6500 2900);
PAINT AQUA (-6500 2900);
FORCEPROP 1 LASTPIN (-6550 2700) $PN 2
J 0
(-6540 2680);
DISPLAY 0.787234 (-6540 2680);
PAINT ORANGE (-6540 2680);
FORCEPROP 1 LASTPIN (-6550 2900) $PN 1
J 0
(-6540 2880);
DISPLAY 0.787234 (-6540 2880);
PAINT ORANGE (-6540 2880);
FORCEPROP 1 LAST PACK_TYPE 0603V
J 0
(-6500 2600);
DISPLAY 0.617021 (-6500 2600);
PAINT SKYBLUE (-6500 2600);
FORCEPROP 1 LAST PART_NUMBER E15431-004
J 0
(-6500 2650);
DISPLAY 0.617021 (-6500 2650);
PAINT BLUE (-6500 2650);
FORCEPROP 1 LAST TOLERANCE 20%
J 0
(-6500 2750);
DISPLAY 0.617021 (-6500 2750);
PAINT SKYBLUE (-6500 2750);
FORCEPROP 1 LAST VOLTAGE 4V
J 0
(-6500 2800);
DISPLAY 0.617021 (-6500 2800);
PAINT SKYBLUE (-6500 2800);
FORCEPROP 0 LAST BOM_DS NOPOP
J 0
(-6494 2552);
DISPLAY 0.638298 (-6494 2552);
PAINT BROWN (-6494 2552);
DISPLAY BOTH (-6494 2552);
FORCEPROP 2 LAST SEC_TYPE 0603V
J 0
(-6500 3000);
DISPLAY 1.021277 (-6500 3000);
PAINT ORANGE (-6500 3000);
DISPLAY INVISIBLE (-6500 3000);
FORCEPROP 0 LAST SEC 1
J 0
(-6500 2950);
DISPLAY 0.680851 (-6500 2950);
PAINT MONO (-6500 2950);
DISPLAY INVISIBLE (-6500 2950);
FORCEPROP 0 LAST ROOM PVDDQ_KLM
J 0
(-6500 3000);
DISPLAY 1.021277 (-6500 3000);
PAINT ORANGE (-6500 3000);
DISPLAY INVISIBLE (-6500 3000);
FORCEPROP 1 LAST PATH I55
J 0
(-6500 2950);
DISPLAY 0.978723 (-6500 2950);
PAINT WHITE (-6500 2950);
DISPLAY INVISIBLE (-6500 2950);
FORCEPROP 2 LAST CDS_LIB dev_discrete
J 0
(-6550 2800);
PAINT MONO (-6550 2800);
DISPLAY INVISIBLE (-6550 2800);
FORCEADD CAP_A..1
(-6950 2800);
FORCEPROP 0 LAST GROUP PWR_MLCC_CAP
J 0
(-6887 2518);
DISPLAY 0.638298 (-6887 2518);
PAINT BROWN (-6887 2518);
DISPLAY BOTH (-6887 2518);
FORCEPROP 1 LAST VOLTAGE 4V
J 0
(-6900 2800);
DISPLAY 0.617021 (-6900 2800);
PAINT SKYBLUE (-6900 2800);
FORCEPROP 1 LAST PART_NUMBER E15431-004
J 0
(-6900 2650);
DISPLAY 0.617021 (-6900 2650);
PAINT BLUE (-6900 2650);
FORCEPROP 1 LASTPIN (-6950 2900) $PN 1
J 0
(-6940 2880);
DISPLAY 0.787234 (-6940 2880);
PAINT ORANGE (-6940 2880);
FORCEPROP 1 LASTPIN (-6950 2700) $PN 2
J 0
(-6940 2680);
DISPLAY 0.787234 (-6940 2680);
PAINT ORANGE (-6940 2680);
FORCEPROP 1 LAST PACK_TYPE 0603V
J 0
(-6900 2600);
DISPLAY 0.617021 (-6900 2600);
PAINT SKYBLUE (-6900 2600);
FORCEPROP 1 LAST MATERIAL X6S
J 0
(-6900 2700);
DISPLAY 0.617021 (-6900 2700);
PAINT SKYBLUE (-6900 2700);
FORCEPROP 1 LAST TOLERANCE 20%
J 0
(-6900 2750);
DISPLAY 0.617021 (-6900 2750);
PAINT SKYBLUE (-6900 2750);
FORCEPROP 1 LAST VALUE 22.0UF
J 0
(-6900 2850);
DISPLAY 0.617021 (-6900 2850);
PAINT SKYBLUE (-6900 2850);
FORCEPROP 1 LAST LOCATION C5G43
J 0
(-6900 2900);
DISPLAY 0.617021 (-6900 2900);
PAINT AQUA (-6900 2900);
FORCEPROP 0 LAST BOM_DS NOPOP
J 0
(-6894 2552);
DISPLAY 0.638298 (-6894 2552);
PAINT BROWN (-6894 2552);
DISPLAY BOTH (-6894 2552);
FORCEPROP 2 LAST SEC_TYPE 0603V
J 0
(-6900 3000);
DISPLAY 1.021277 (-6900 3000);
PAINT ORANGE (-6900 3000);
DISPLAY INVISIBLE (-6900 3000);
FORCEPROP 0 LAST SEC 1
J 0
(-6900 2950);
DISPLAY 0.680851 (-6900 2950);
PAINT MONO (-6900 2950);
DISPLAY INVISIBLE (-6900 2950);
FORCEPROP 2 LAST CDS_LIB dev_discrete
J 0
(-6950 2800);
PAINT MONO (-6950 2800);
DISPLAY INVISIBLE (-6950 2800);
FORCEPROP 1 LAST PATH I56
J 0
(-6900 2950);
DISPLAY 0.978723 (-6900 2950);
PAINT WHITE (-6900 2950);
DISPLAY INVISIBLE (-6900 2950);
FORCEPROP 0 LAST ROOM PVDDQ_KLM
J 0
(-6900 3000);
DISPLAY 1.021277 (-6900 3000);
PAINT ORANGE (-6900 3000);
DISPLAY INVISIBLE (-6900 3000);
FORCEADD CAP_A..1
(-4950 2800);
FORCEPROP 0 LAST GROUP PWR_MLCC_CAP
J 0
(-4893 2448);
DISPLAY 0.638298 (-4893 2448);
PAINT BROWN (-4893 2448);
DISPLAY BOTH (-4893 2448);
FORCEPROP 1 LAST PART_NUMBER E15431-004
J 0
(-4900 2650);
DISPLAY 0.617021 (-4900 2650);
PAINT BLUE (-4900 2650);
FORCEPROP 1 LAST MATERIAL X6S
J 0
(-4900 2700);
DISPLAY 0.617021 (-4900 2700);
PAINT SKYBLUE (-4900 2700);
FORCEPROP 1 LASTPIN (-4950 2900) $PN 1
J 0
(-4940 2880);
DISPLAY 0.787234 (-4940 2880);
PAINT ORANGE (-4940 2880);
FORCEPROP 1 LASTPIN (-4950 2700) $PN 2
J 0
(-4940 2680);
DISPLAY 0.787234 (-4940 2680);
PAINT ORANGE (-4940 2680);
FORCEPROP 1 LAST PACK_TYPE 0603V
J 0
(-4900 2600);
DISPLAY 0.617021 (-4900 2600);
PAINT SKYBLUE (-4900 2600);
FORCEPROP 1 LAST TOLERANCE 20%
J 0
(-4900 2750);
DISPLAY 0.617021 (-4900 2750);
PAINT SKYBLUE (-4900 2750);
FORCEPROP 1 LAST LOCATION C5G48
J 0
(-4900 2900);
DISPLAY 0.617021 (-4900 2900);
PAINT AQUA (-4900 2900);
FORCEPROP 1 LAST VOLTAGE 4V
J 0
(-4900 2800);
DISPLAY 0.617021 (-4900 2800);
PAINT SKYBLUE (-4900 2800);
FORCEPROP 1 LAST VALUE 22.0UF
J 0
(-4900 2850);
DISPLAY 0.617021 (-4900 2850);
PAINT SKYBLUE (-4900 2850);
FORCEPROP 0 LAST BOM_DS NOPOP
J 0
(-4894 2552);
DISPLAY 0.638298 (-4894 2552);
PAINT BROWN (-4894 2552);
DISPLAY BOTH (-4894 2552);
FORCEPROP 2 LAST SEC_TYPE 0603V
J 0
(-4900 3000);
DISPLAY 1.021277 (-4900 3000);
PAINT ORANGE (-4900 3000);
DISPLAY INVISIBLE (-4900 3000);
FORCEPROP 0 LAST SEC 1
J 0
(-4900 2950);
DISPLAY 0.680851 (-4900 2950);
PAINT MONO (-4900 2950);
DISPLAY INVISIBLE (-4900 2950);
FORCEPROP 0 LAST ROOM PVDDQ_KLM
J 0
(-4900 3000);
DISPLAY 1.021277 (-4900 3000);
PAINT ORANGE (-4900 3000);
DISPLAY INVISIBLE (-4900 3000);
FORCEPROP 1 LAST PATH I57
J 0
(-4900 2950);
DISPLAY 0.978723 (-4900 2950);
PAINT WHITE (-4900 2950);
DISPLAY INVISIBLE (-4900 2950);
FORCEPROP 2 LAST CDS_LIB dev_discrete
J 0
(-4950 2800);
PAINT MONO (-4950 2800);
DISPLAY INVISIBLE (-4950 2800);
FORCEADD CAP_A..1
(-5350 2800);
FORCEPROP 0 LAST GROUP PWR_MLCC_CAP
J 0
(-5303 2508);
DISPLAY 0.638298 (-5303 2508);
PAINT BROWN (-5303 2508);
DISPLAY BOTH (-5303 2508);
FORCEPROP 1 LAST PACK_TYPE 0603V
J 0
(-5300 2600);
DISPLAY 0.617021 (-5300 2600);
PAINT SKYBLUE (-5300 2600);
FORCEPROP 1 LAST PART_NUMBER E15431-004
J 0
(-5300 2650);
DISPLAY 0.617021 (-5300 2650);
PAINT BLUE (-5300 2650);
FORCEPROP 1 LAST VOLTAGE 4V
J 0
(-5300 2800);
DISPLAY 0.617021 (-5300 2800);
PAINT SKYBLUE (-5300 2800);
FORCEPROP 1 LAST TOLERANCE 20%
J 0
(-5300 2750);
DISPLAY 0.617021 (-5300 2750);
PAINT SKYBLUE (-5300 2750);
FORCEPROP 1 LAST MATERIAL X6S
J 0
(-5300 2700);
DISPLAY 0.617021 (-5300 2700);
PAINT SKYBLUE (-5300 2700);
FORCEPROP 1 LASTPIN (-5350 2700) $PN 2
J 0
(-5340 2680);
DISPLAY 0.787234 (-5340 2680);
PAINT ORANGE (-5340 2680);
FORCEPROP 1 LASTPIN (-5350 2900) $PN 1
J 0
(-5340 2880);
DISPLAY 0.787234 (-5340 2880);
PAINT ORANGE (-5340 2880);
FORCEPROP 1 LAST VALUE 22.0UF
J 0
(-5300 2850);
DISPLAY 0.617021 (-5300 2850);
PAINT SKYBLUE (-5300 2850);
FORCEPROP 1 LAST LOCATION C5G47
J 0
(-5300 2900);
DISPLAY 0.617021 (-5300 2900);
PAINT AQUA (-5300 2900);
FORCEPROP 0 LAST BOM_DS NOPOP
J 0
(-5294 2552);
DISPLAY 0.638298 (-5294 2552);
PAINT BROWN (-5294 2552);
DISPLAY BOTH (-5294 2552);
FORCEPROP 2 LAST CDS_LIB dev_discrete
J 0
(-5350 2800);
PAINT MONO (-5350 2800);
DISPLAY INVISIBLE (-5350 2800);
FORCEPROP 1 LAST PATH I58
J 0
(-5300 2950);
DISPLAY 0.978723 (-5300 2950);
PAINT WHITE (-5300 2950);
DISPLAY INVISIBLE (-5300 2950);
FORCEPROP 0 LAST ROOM PVDDQ_KLM
J 0
(-5300 3000);
DISPLAY 1.021277 (-5300 3000);
PAINT ORANGE (-5300 3000);
DISPLAY INVISIBLE (-5300 3000);
FORCEPROP 0 LAST SEC 1
J 0
(-5300 2950);
DISPLAY 0.680851 (-5300 2950);
PAINT MONO (-5300 2950);
DISPLAY INVISIBLE (-5300 2950);
FORCEPROP 2 LAST SEC_TYPE 0603V
J 0
(-5300 3000);
DISPLAY 1.021277 (-5300 3000);
PAINT ORANGE (-5300 3000);
DISPLAY INVISIBLE (-5300 3000);
FORCEADD CAP_A..1
(-5750 2800);
FORCEPROP 0 LAST GROUP PWR_MLCC_CAP
J 0
(-5710 2461);
DISPLAY 0.638298 (-5710 2461);
PAINT BROWN (-5710 2461);
DISPLAY BOTH (-5710 2461);
FORCEPROP 1 LAST LOCATION C5G46
J 0
(-5700 2900);
DISPLAY 0.617021 (-5700 2900);
PAINT AQUA (-5700 2900);
FORCEPROP 1 LAST VOLTAGE 4V
J 0
(-5700 2800);
DISPLAY 0.617021 (-5700 2800);
PAINT SKYBLUE (-5700 2800);
FORCEPROP 1 LAST PART_NUMBER E15431-004
J 0
(-5700 2650);
DISPLAY 0.617021 (-5700 2650);
PAINT BLUE (-5700 2650);
FORCEPROP 1 LAST PACK_TYPE 0603V
J 0
(-5700 2600);
DISPLAY 0.617021 (-5700 2600);
PAINT SKYBLUE (-5700 2600);
FORCEPROP 1 LASTPIN (-5750 2900) $PN 1
J 0
(-5740 2880);
DISPLAY 0.787234 (-5740 2880);
PAINT ORANGE (-5740 2880);
FORCEPROP 1 LASTPIN (-5750 2700) $PN 2
J 0
(-5740 2680);
DISPLAY 0.787234 (-5740 2680);
PAINT ORANGE (-5740 2680);
FORCEPROP 1 LAST TOLERANCE 20%
J 0
(-5700 2750);
DISPLAY 0.617021 (-5700 2750);
PAINT SKYBLUE (-5700 2750);
FORCEPROP 1 LAST MATERIAL X6S
J 0
(-5700 2700);
DISPLAY 0.617021 (-5700 2700);
PAINT SKYBLUE (-5700 2700);
FORCEPROP 1 LAST VALUE 22.0UF
J 0
(-5700 2850);
DISPLAY 0.617021 (-5700 2850);
PAINT SKYBLUE (-5700 2850);
FORCEPROP 0 LAST BOM_DS NOPOP
J 0
(-5694 2552);
DISPLAY 0.638298 (-5694 2552);
PAINT BROWN (-5694 2552);
DISPLAY BOTH (-5694 2552);
FORCEPROP 2 LAST SEC_TYPE 0603V
J 0
(-5700 3000);
DISPLAY 1.021277 (-5700 3000);
PAINT ORANGE (-5700 3000);
DISPLAY INVISIBLE (-5700 3000);
FORCEPROP 0 LAST SEC 1
J 0
(-5700 2950);
DISPLAY 0.680851 (-5700 2950);
PAINT MONO (-5700 2950);
DISPLAY INVISIBLE (-5700 2950);
FORCEPROP 0 LAST ROOM PVDDQ_KLM
J 0
(-5700 3000);
DISPLAY 1.021277 (-5700 3000);
PAINT ORANGE (-5700 3000);
DISPLAY INVISIBLE (-5700 3000);
FORCEPROP 1 LAST PATH I59
J 0
(-5700 2950);
DISPLAY 0.978723 (-5700 2950);
PAINT WHITE (-5700 2950);
DISPLAY INVISIBLE (-5700 2950);
FORCEPROP 2 LAST CDS_LIB dev_discrete
J 0
(-5750 2800);
PAINT MONO (-5750 2800);
DISPLAY INVISIBLE (-5750 2800);
FORCEADD CAP_A..1
(-6150 2800);
FORCEPROP 0 LAST GROUP PWR_MLCC_CAP
J 0
(-6098 2516);
DISPLAY 0.638298 (-6098 2516);
PAINT BROWN (-6098 2516);
DISPLAY BOTH (-6098 2516);
FORCEPROP 1 LAST PART_NUMBER E15431-004
J 0
(-6100 2650);
DISPLAY 0.617021 (-6100 2650);
PAINT BLUE (-6100 2650);
FORCEPROP 1 LAST PACK_TYPE 0603V
J 0
(-6100 2600);
DISPLAY 0.617021 (-6100 2600);
PAINT SKYBLUE (-6100 2600);
FORCEPROP 1 LAST LOCATION C5G45
J 0
(-6100 2900);
DISPLAY 0.617021 (-6100 2900);
PAINT AQUA (-6100 2900);
FORCEPROP 1 LAST TOLERANCE 20%
J 0
(-6100 2750);
DISPLAY 0.617021 (-6100 2750);
PAINT SKYBLUE (-6100 2750);
FORCEPROP 1 LAST MATERIAL X6S
J 0
(-6100 2700);
DISPLAY 0.617021 (-6100 2700);
PAINT SKYBLUE (-6100 2700);
FORCEPROP 1 LASTPIN (-6150 2900) $PN 1
J 0
(-6140 2880);
DISPLAY 0.787234 (-6140 2880);
PAINT ORANGE (-6140 2880);
FORCEPROP 1 LASTPIN (-6150 2700) $PN 2
J 0
(-6140 2680);
DISPLAY 0.787234 (-6140 2680);
PAINT ORANGE (-6140 2680);
FORCEPROP 1 LAST VALUE 22.0UF
J 0
(-6100 2850);
DISPLAY 0.617021 (-6100 2850);
PAINT SKYBLUE (-6100 2850);
FORCEPROP 1 LAST VOLTAGE 4V
J 0
(-6100 2800);
DISPLAY 0.617021 (-6100 2800);
PAINT SKYBLUE (-6100 2800);
FORCEPROP 0 LAST BOM_DS NOPOP
J 0
(-6094 2552);
DISPLAY 0.638298 (-6094 2552);
PAINT BROWN (-6094 2552);
DISPLAY BOTH (-6094 2552);
FORCEPROP 2 LAST SEC_TYPE 0603V
J 0
(-6100 3000);
DISPLAY 1.021277 (-6100 3000);
PAINT ORANGE (-6100 3000);
DISPLAY INVISIBLE (-6100 3000);
FORCEPROP 0 LAST SEC 1
J 0
(-6100 2950);
DISPLAY 0.680851 (-6100 2950);
PAINT MONO (-6100 2950);
DISPLAY INVISIBLE (-6100 2950);
FORCEPROP 0 LAST ROOM PVDDQ_KLM
J 0
(-6100 3000);
DISPLAY 1.021277 (-6100 3000);
PAINT ORANGE (-6100 3000);
DISPLAY INVISIBLE (-6100 3000);
FORCEPROP 1 LAST PATH I60
J 0
(-6100 2950);
DISPLAY 0.978723 (-6100 2950);
PAINT WHITE (-6100 2950);
DISPLAY INVISIBLE (-6100 2950);
FORCEPROP 2 LAST CDS_LIB dev_discrete
J 0
(-6150 2800);
PAINT MONO (-6150 2800);
DISPLAY INVISIBLE (-6150 2800);
FORCEADD CAP_A..1
(-4550 2800);
FORCEPROP 0 LAST GROUP PWR_MLCC_CAP
J 0
(-4500 2495);
DISPLAY 0.638298 (-4500 2495);
PAINT BROWN (-4500 2495);
DISPLAY BOTH (-4500 2495);
FORCEPROP 1 LASTPIN (-4550 2700) $PN 2
J 0
(-4540 2680);
DISPLAY 0.787234 (-4540 2680);
PAINT ORANGE (-4540 2680);
FORCEPROP 1 LAST PART_NUMBER E15431-004
J 0
(-4500 2650);
DISPLAY 0.617021 (-4500 2650);
PAINT BLUE (-4500 2650);
FORCEPROP 1 LAST TOLERANCE 20%
J 0
(-4500 2750);
DISPLAY 0.617021 (-4500 2750);
PAINT SKYBLUE (-4500 2750);
FORCEPROP 1 LAST MATERIAL X6S
J 0
(-4500 2700);
DISPLAY 0.617021 (-4500 2700);
PAINT SKYBLUE (-4500 2700);
FORCEPROP 1 LAST PACK_TYPE 0603V
J 0
(-4500 2600);
DISPLAY 0.617021 (-4500 2600);
PAINT SKYBLUE (-4500 2600);
FORCEPROP 1 LASTPIN (-4550 2900) $PN 1
J 0
(-4540 2880);
DISPLAY 0.787234 (-4540 2880);
PAINT ORANGE (-4540 2880);
FORCEPROP 1 LAST LOCATION C5G49
J 0
(-4500 2900);
DISPLAY 0.617021 (-4500 2900);
PAINT AQUA (-4500 2900);
FORCEPROP 1 LAST VOLTAGE 4V
J 0
(-4500 2800);
DISPLAY 0.617021 (-4500 2800);
PAINT SKYBLUE (-4500 2800);
FORCEPROP 1 LAST VALUE 22.0UF
J 0
(-4500 2850);
DISPLAY 0.617021 (-4500 2850);
PAINT SKYBLUE (-4500 2850);
FORCEPROP 0 LAST BOM_DS NOPOP
J 0
(-4494 2552);
DISPLAY 0.638298 (-4494 2552);
PAINT BROWN (-4494 2552);
DISPLAY BOTH (-4494 2552);
FORCEPROP 2 LAST CDS_LIB dev_discrete
J 0
(-4550 2800);
PAINT MONO (-4550 2800);
DISPLAY INVISIBLE (-4550 2800);
FORCEPROP 1 LAST PATH I61
J 0
(-4500 2950);
DISPLAY 0.978723 (-4500 2950);
PAINT WHITE (-4500 2950);
DISPLAY INVISIBLE (-4500 2950);
FORCEPROP 0 LAST ROOM PVDDQ_KLM
J 0
(-4500 3000);
DISPLAY 1.021277 (-4500 3000);
PAINT ORANGE (-4500 3000);
DISPLAY INVISIBLE (-4500 3000);
FORCEPROP 0 LAST SEC 1
J 0
(-4500 2950);
DISPLAY 0.680851 (-4500 2950);
PAINT MONO (-4500 2950);
DISPLAY INVISIBLE (-4500 2950);
FORCEPROP 2 LAST SEC_TYPE 0603V
J 0
(-4500 3000);
DISPLAY 1.021277 (-4500 3000);
PAINT ORANGE (-4500 3000);
DISPLAY INVISIBLE (-4500 3000);
FORCEADD CAP_A..1
(-6150 1850);
FORCEPROP 1 LASTPIN (-6150 1750) $PN 2
J 0
(-6140 1730);
DISPLAY 0.787234 (-6140 1730);
PAINT ORANGE (-6140 1730);
FORCEPROP 1 LAST PACK_TYPE 0603V
J 0
(-6100 1650);
DISPLAY 0.617021 (-6100 1650);
PAINT SKYBLUE (-6100 1650);
FORCEPROP 1 LAST MATERIAL X6S
J 0
(-6100 1750);
DISPLAY 0.617021 (-6100 1750);
PAINT SKYBLUE (-6100 1750);
FORCEPROP 1 LAST TOLERANCE 20%
J 0
(-6100 1800);
DISPLAY 0.617021 (-6100 1800);
PAINT SKYBLUE (-6100 1800);
FORCEPROP 1 LAST VALUE 22.0UF
J 0
(-6100 1900);
DISPLAY 0.617021 (-6100 1900);
PAINT SKYBLUE (-6100 1900);
FORCEPROP 1 LAST VOLTAGE 4V
J 0
(-6100 1850);
DISPLAY 0.617021 (-6100 1850);
PAINT SKYBLUE (-6100 1850);
FORCEPROP 1 LASTPIN (-6150 1950) $PN 1
J 0
(-6140 1930);
DISPLAY 0.787234 (-6140 1930);
PAINT ORANGE (-6140 1930);
FORCEPROP 1 LAST LOCATION C5G54
J 0
(-6100 1950);
DISPLAY 0.617021 (-6100 1950);
PAINT AQUA (-6100 1950);
FORCEPROP 0 LAST GROUP PWR_MLCC_CAP
J 0
(-6109 1568);
DISPLAY 0.638298 (-6109 1568);
PAINT BROWN (-6109 1568);
DISPLAY BOTH (-6109 1568);
FORCEPROP 1 LAST PART_NUMBER E15431-004
J 0
(-6100 1700);
DISPLAY 0.617021 (-6100 1700);
PAINT BLUE (-6100 1700);
FORCEPROP 0 LAST BOM_DS NOPOP
J 0
(-6094 1602);
DISPLAY 0.638298 (-6094 1602);
PAINT BROWN (-6094 1602);
DISPLAY BOTH (-6094 1602);
FORCEPROP 2 LAST SEC_TYPE 0603V
J 0
(-6100 2050);
DISPLAY 1.021277 (-6100 2050);
PAINT ORANGE (-6100 2050);
DISPLAY INVISIBLE (-6100 2050);
FORCEPROP 0 LAST SEC 1
J 0
(-6100 2000);
DISPLAY 0.680851 (-6100 2000);
PAINT MONO (-6100 2000);
DISPLAY INVISIBLE (-6100 2000);
FORCEPROP 0 LAST ROOM PVDDQ_KLM
J 0
(-6100 2050);
DISPLAY 1.021277 (-6100 2050);
PAINT ORANGE (-6100 2050);
DISPLAY INVISIBLE (-6100 2050);
FORCEPROP 1 LAST PATH I62
J 0
(-6100 2000);
DISPLAY 0.978723 (-6100 2000);
PAINT WHITE (-6100 2000);
DISPLAY INVISIBLE (-6100 2000);
FORCEPROP 2 LAST CDS_LIB dev_discrete
J 0
(-6150 1850);
PAINT MONO (-6150 1850);
DISPLAY INVISIBLE (-6150 1850);
FORCEADD CAP_A..1
(-4550 1850);
FORCEPROP 0 LAST GROUP PWR_MLCC_CAP
J 0
(-4505 1542);
DISPLAY 0.638298 (-4505 1542);
PAINT BROWN (-4505 1542);
DISPLAY BOTH (-4505 1542);
FORCEPROP 1 LAST TOLERANCE 20%
J 0
(-4500 1800);
DISPLAY 0.617021 (-4500 1800);
PAINT SKYBLUE (-4500 1800);
FORCEPROP 1 LAST VOLTAGE 4V
J 0
(-4500 1850);
DISPLAY 0.617021 (-4500 1850);
PAINT SKYBLUE (-4500 1850);
FORCEPROP 1 LAST MATERIAL X6S
J 0
(-4500 1750);
DISPLAY 0.617021 (-4500 1750);
PAINT SKYBLUE (-4500 1750);
FORCEPROP 1 LAST VALUE 22.0UF
J 0
(-4500 1900);
DISPLAY 0.617021 (-4500 1900);
PAINT SKYBLUE (-4500 1900);
FORCEPROP 1 LAST PACK_TYPE 0603V
J 0
(-4500 1650);
DISPLAY 0.617021 (-4500 1650);
PAINT SKYBLUE (-4500 1650);
FORCEPROP 1 LASTPIN (-4550 1750) $PN 2
J 0
(-4540 1730);
DISPLAY 0.787234 (-4540 1730);
PAINT ORANGE (-4540 1730);
FORCEPROP 1 LASTPIN (-4550 1950) $PN 1
J 0
(-4540 1930);
DISPLAY 0.787234 (-4540 1930);
PAINT ORANGE (-4540 1930);
FORCEPROP 1 LAST LOCATION C5G58
J 0
(-4500 1950);
DISPLAY 0.617021 (-4500 1950);
PAINT AQUA (-4500 1950);
FORCEPROP 1 LAST PART_NUMBER E15431-004
J 0
(-4500 1700);
DISPLAY 0.617021 (-4500 1700);
PAINT BLUE (-4500 1700);
FORCEPROP 0 LAST BOM_DS NOPOP
J 0
(-4494 1602);
DISPLAY 0.638298 (-4494 1602);
PAINT BROWN (-4494 1602);
DISPLAY BOTH (-4494 1602);
FORCEPROP 2 LAST CDS_LIB dev_discrete
J 0
(-4550 1850);
PAINT MONO (-4550 1850);
DISPLAY INVISIBLE (-4550 1850);
FORCEPROP 1 LAST PATH I63
J 0
(-4500 2000);
DISPLAY 0.978723 (-4500 2000);
PAINT WHITE (-4500 2000);
DISPLAY INVISIBLE (-4500 2000);
FORCEPROP 0 LAST ROOM PVDDQ_KLM
J 0
(-4500 2050);
DISPLAY 1.021277 (-4500 2050);
PAINT ORANGE (-4500 2050);
DISPLAY INVISIBLE (-4500 2050);
FORCEPROP 0 LAST SEC 1
J 0
(-4500 2000);
DISPLAY 0.680851 (-4500 2000);
PAINT MONO (-4500 2000);
DISPLAY INVISIBLE (-4500 2000);
FORCEPROP 2 LAST SEC_TYPE 0603V
J 0
(-4500 2050);
DISPLAY 1.021277 (-4500 2050);
PAINT ORANGE (-4500 2050);
DISPLAY INVISIBLE (-4500 2050);
FORCEADD CAP_A..1
(-4950 1850);
FORCEPROP 0 LAST GROUP PWR_MLCC_CAP
J 0
(-4896 1512);
DISPLAY 0.638298 (-4896 1512);
PAINT BROWN (-4896 1512);
DISPLAY BOTH (-4896 1512);
FORCEPROP 1 LAST MATERIAL X6S
J 0
(-4900 1750);
DISPLAY 0.617021 (-4900 1750);
PAINT SKYBLUE (-4900 1750);
FORCEPROP 1 LAST PART_NUMBER E15431-004
J 0
(-4900 1700);
DISPLAY 0.617021 (-4900 1700);
PAINT BLUE (-4900 1700);
FORCEPROP 1 LAST PACK_TYPE 0603V
J 0
(-4900 1650);
DISPLAY 0.617021 (-4900 1650);
PAINT SKYBLUE (-4900 1650);
FORCEPROP 1 LASTPIN (-4950 1950) $PN 1
J 0
(-4940 1930);
DISPLAY 0.787234 (-4940 1930);
PAINT ORANGE (-4940 1930);
FORCEPROP 1 LASTPIN (-4950 1750) $PN 2
J 0
(-4940 1730);
DISPLAY 0.787234 (-4940 1730);
PAINT ORANGE (-4940 1730);
FORCEPROP 1 LAST VALUE 22.0UF
J 0
(-4900 1900);
DISPLAY 0.617021 (-4900 1900);
PAINT SKYBLUE (-4900 1900);
FORCEPROP 1 LAST TOLERANCE 20%
J 0
(-4900 1800);
DISPLAY 0.617021 (-4900 1800);
PAINT SKYBLUE (-4900 1800);
FORCEPROP 1 LAST LOCATION C5G57
J 0
(-4900 1950);
DISPLAY 0.617021 (-4900 1950);
PAINT AQUA (-4900 1950);
FORCEPROP 1 LAST VOLTAGE 4V
J 0
(-4900 1850);
DISPLAY 0.617021 (-4900 1850);
PAINT SKYBLUE (-4900 1850);
FORCEPROP 0 LAST BOM_DS NOPOP
J 0
(-4894 1602);
DISPLAY 0.638298 (-4894 1602);
PAINT BROWN (-4894 1602);
DISPLAY BOTH (-4894 1602);
FORCEPROP 2 LAST SEC_TYPE 0603V
J 0
(-4900 2050);
DISPLAY 1.021277 (-4900 2050);
PAINT ORANGE (-4900 2050);
DISPLAY INVISIBLE (-4900 2050);
FORCEPROP 0 LAST SEC 1
J 0
(-4900 2000);
DISPLAY 0.680851 (-4900 2000);
PAINT MONO (-4900 2000);
DISPLAY INVISIBLE (-4900 2000);
FORCEPROP 0 LAST ROOM PVDDQ_KLM
J 0
(-4900 2050);
DISPLAY 1.021277 (-4900 2050);
PAINT ORANGE (-4900 2050);
DISPLAY INVISIBLE (-4900 2050);
FORCEPROP 1 LAST PATH I64
J 0
(-4900 2000);
DISPLAY 0.978723 (-4900 2000);
PAINT WHITE (-4900 2000);
DISPLAY INVISIBLE (-4900 2000);
FORCEPROP 2 LAST CDS_LIB dev_discrete
J 0
(-4950 1850);
PAINT MONO (-4950 1850);
DISPLAY INVISIBLE (-4950 1850);
FORCEADD CAP_A..1
(-5350 1850);
FORCEPROP 0 LAST GROUP PWR_MLCC_CAP
J 0
(-5315 1555);
DISPLAY 0.638298 (-5315 1555);
PAINT BROWN (-5315 1555);
DISPLAY BOTH (-5315 1555);
FORCEPROP 1 LAST LOCATION C5G56
J 0
(-5300 1950);
DISPLAY 0.617021 (-5300 1950);
PAINT AQUA (-5300 1950);
FORCEPROP 1 LAST PART_NUMBER E15431-004
J 0
(-5300 1700);
DISPLAY 0.617021 (-5300 1700);
PAINT BLUE (-5300 1700);
FORCEPROP 1 LAST TOLERANCE 20%
J 0
(-5300 1800);
DISPLAY 0.617021 (-5300 1800);
PAINT SKYBLUE (-5300 1800);
FORCEPROP 1 LAST VOLTAGE 4V
J 0
(-5300 1850);
DISPLAY 0.617021 (-5300 1850);
PAINT SKYBLUE (-5300 1850);
FORCEPROP 1 LAST VALUE 22.0UF
J 0
(-5300 1900);
DISPLAY 0.617021 (-5300 1900);
PAINT SKYBLUE (-5300 1900);
FORCEPROP 1 LAST MATERIAL X6S
J 0
(-5300 1750);
DISPLAY 0.617021 (-5300 1750);
PAINT SKYBLUE (-5300 1750);
FORCEPROP 1 LASTPIN (-5350 1750) $PN 2
J 0
(-5340 1730);
DISPLAY 0.787234 (-5340 1730);
PAINT ORANGE (-5340 1730);
FORCEPROP 1 LAST PACK_TYPE 0603V
J 0
(-5300 1650);
DISPLAY 0.617021 (-5300 1650);
PAINT SKYBLUE (-5300 1650);
FORCEPROP 1 LASTPIN (-5350 1950) $PN 1
J 0
(-5340 1930);
DISPLAY 0.787234 (-5340 1930);
PAINT ORANGE (-5340 1930);
FORCEPROP 0 LAST BOM_DS NOPOP
J 0
(-5294 1602);
DISPLAY 0.638298 (-5294 1602);
PAINT BROWN (-5294 1602);
DISPLAY BOTH (-5294 1602);
FORCEPROP 2 LAST CDS_LIB dev_discrete
J 0
(-5350 1850);
PAINT MONO (-5350 1850);
DISPLAY INVISIBLE (-5350 1850);
FORCEPROP 1 LAST PATH I65
J 0
(-5300 2000);
DISPLAY 0.978723 (-5300 2000);
PAINT WHITE (-5300 2000);
DISPLAY INVISIBLE (-5300 2000);
FORCEPROP 0 LAST ROOM PVDDQ_KLM
J 0
(-5300 2050);
DISPLAY 1.021277 (-5300 2050);
PAINT ORANGE (-5300 2050);
DISPLAY INVISIBLE (-5300 2050);
FORCEPROP 0 LAST SEC 1
J 0
(-5300 2000);
DISPLAY 0.680851 (-5300 2000);
PAINT MONO (-5300 2000);
DISPLAY INVISIBLE (-5300 2000);
FORCEPROP 2 LAST SEC_TYPE 0603V
J 0
(-5300 2050);
DISPLAY 1.021277 (-5300 2050);
PAINT ORANGE (-5300 2050);
DISPLAY INVISIBLE (-5300 2050);
FORCEADD CAP_A..1
(-5750 1850);
FORCEPROP 0 LAST GROUP PWR_MLCC_CAP
J 0
(-5697 1502);
DISPLAY 0.638298 (-5697 1502);
PAINT BROWN (-5697 1502);
DISPLAY BOTH (-5697 1502);
FORCEPROP 1 LAST PART_NUMBER E15431-004
J 0
(-5700 1700);
DISPLAY 0.617021 (-5700 1700);
PAINT BLUE (-5700 1700);
FORCEPROP 1 LAST TOLERANCE 20%
J 0
(-5700 1800);
DISPLAY 0.617021 (-5700 1800);
PAINT SKYBLUE (-5700 1800);
FORCEPROP 1 LASTPIN (-5750 1950) $PN 1
J 0
(-5740 1930);
DISPLAY 0.787234 (-5740 1930);
PAINT ORANGE (-5740 1930);
FORCEPROP 1 LASTPIN (-5750 1750) $PN 2
J 0
(-5740 1730);
DISPLAY 0.787234 (-5740 1730);
PAINT ORANGE (-5740 1730);
FORCEPROP 1 LAST PACK_TYPE 0603V
J 0
(-5700 1650);
DISPLAY 0.617021 (-5700 1650);
PAINT SKYBLUE (-5700 1650);
FORCEPROP 1 LAST MATERIAL X6S
J 0
(-5700 1750);
DISPLAY 0.617021 (-5700 1750);
PAINT SKYBLUE (-5700 1750);
FORCEPROP 1 LAST VOLTAGE 4V
J 0
(-5700 1850);
DISPLAY 0.617021 (-5700 1850);
PAINT SKYBLUE (-5700 1850);
FORCEPROP 1 LAST VALUE 22.0UF
J 0
(-5700 1900);
DISPLAY 0.617021 (-5700 1900);
PAINT SKYBLUE (-5700 1900);
FORCEPROP 1 LAST LOCATION C5G55
J 0
(-5700 1950);
DISPLAY 0.617021 (-5700 1950);
PAINT AQUA (-5700 1950);
FORCEPROP 0 LAST BOM_DS NOPOP
J 0
(-5694 1602);
DISPLAY 0.638298 (-5694 1602);
PAINT BROWN (-5694 1602);
DISPLAY BOTH (-5694 1602);
FORCEPROP 2 LAST SEC_TYPE 0603V
J 0
(-5700 2050);
DISPLAY 1.021277 (-5700 2050);
PAINT ORANGE (-5700 2050);
DISPLAY INVISIBLE (-5700 2050);
FORCEPROP 0 LAST SEC 1
J 0
(-5700 2000);
DISPLAY 0.680851 (-5700 2000);
PAINT MONO (-5700 2000);
DISPLAY INVISIBLE (-5700 2000);
FORCEPROP 0 LAST ROOM PVDDQ_KLM
J 0
(-5700 2050);
DISPLAY 1.021277 (-5700 2050);
PAINT ORANGE (-5700 2050);
DISPLAY INVISIBLE (-5700 2050);
FORCEPROP 1 LAST PATH I66
J 0
(-5700 2000);
DISPLAY 0.978723 (-5700 2000);
PAINT WHITE (-5700 2000);
DISPLAY INVISIBLE (-5700 2000);
FORCEPROP 2 LAST CDS_LIB dev_discrete
J 0
(-5750 1850);
PAINT MONO (-5750 1850);
DISPLAY INVISIBLE (-5750 1850);
FORCEADD CAP_A..1
(-6550 1850);
FORCEPROP 0 LAST GROUP PWR_MLCC_CAP
J 0
(-6499 1509);
DISPLAY 0.638298 (-6499 1509);
PAINT BROWN (-6499 1509);
DISPLAY BOTH (-6499 1509);
FORCEPROP 1 LAST TOLERANCE 20%
J 0
(-6500 1800);
DISPLAY 0.617021 (-6500 1800);
PAINT SKYBLUE (-6500 1800);
FORCEPROP 1 LAST PART_NUMBER E15431-004
J 0
(-6500 1700);
DISPLAY 0.617021 (-6500 1700);
PAINT BLUE (-6500 1700);
FORCEPROP 1 LASTPIN (-6550 1950) $PN 1
J 0
(-6540 1930);
DISPLAY 0.787234 (-6540 1930);
PAINT ORANGE (-6540 1930);
FORCEPROP 1 LASTPIN (-6550 1750) $PN 2
J 0
(-6540 1730);
DISPLAY 0.787234 (-6540 1730);
PAINT ORANGE (-6540 1730);
FORCEPROP 1 LAST PACK_TYPE 0603V
J 0
(-6500 1650);
DISPLAY 0.617021 (-6500 1650);
PAINT SKYBLUE (-6500 1650);
FORCEPROP 1 LAST VOLTAGE 4V
J 0
(-6500 1850);
DISPLAY 0.617021 (-6500 1850);
PAINT SKYBLUE (-6500 1850);
FORCEPROP 1 LAST MATERIAL X6S
J 0
(-6500 1750);
DISPLAY 0.617021 (-6500 1750);
PAINT SKYBLUE (-6500 1750);
FORCEPROP 1 LAST LOCATION C5G53
J 0
(-6500 1950);
DISPLAY 0.617021 (-6500 1950);
PAINT AQUA (-6500 1950);
FORCEPROP 1 LAST VALUE 22.0UF
J 0
(-6500 1900);
DISPLAY 0.617021 (-6500 1900);
PAINT SKYBLUE (-6500 1900);
FORCEPROP 0 LAST BOM_DS NOPOP
J 0
(-6494 1602);
DISPLAY 0.638298 (-6494 1602);
PAINT BROWN (-6494 1602);
DISPLAY BOTH (-6494 1602);
FORCEPROP 2 LAST SEC_TYPE 0603V
J 0
(-6500 2050);
DISPLAY 1.021277 (-6500 2050);
PAINT ORANGE (-6500 2050);
DISPLAY INVISIBLE (-6500 2050);
FORCEPROP 0 LAST SEC 1
J 0
(-6500 2000);
DISPLAY 0.680851 (-6500 2000);
PAINT MONO (-6500 2000);
DISPLAY INVISIBLE (-6500 2000);
FORCEPROP 0 LAST ROOM PVDDQ_KLM
J 0
(-6500 2050);
DISPLAY 1.021277 (-6500 2050);
PAINT ORANGE (-6500 2050);
DISPLAY INVISIBLE (-6500 2050);
FORCEPROP 1 LAST PATH I67
J 0
(-6500 2000);
DISPLAY 0.978723 (-6500 2000);
PAINT WHITE (-6500 2000);
DISPLAY INVISIBLE (-6500 2000);
FORCEPROP 2 LAST CDS_LIB dev_discrete
J 0
(-6550 1850);
PAINT MONO (-6550 1850);
DISPLAY INVISIBLE (-6550 1850);
FORCEADD CAP_A..1
(-6950 1850);
FORCEPROP 0 LAST GROUP PWR_MLCC_CAP
J 0
(-6895 1559);
DISPLAY 0.638298 (-6895 1559);
PAINT BROWN (-6895 1559);
DISPLAY BOTH (-6895 1559);
FORCEPROP 1 LAST VALUE 22.0UF
J 0
(-6900 1900);
DISPLAY 0.617021 (-6900 1900);
PAINT SKYBLUE (-6900 1900);
FORCEPROP 1 LAST VOLTAGE 4V
J 0
(-6900 1850);
DISPLAY 0.617021 (-6900 1850);
PAINT SKYBLUE (-6900 1850);
FORCEPROP 1 LAST TOLERANCE 20%
J 0
(-6900 1800);
DISPLAY 0.617021 (-6900 1800);
PAINT SKYBLUE (-6900 1800);
FORCEPROP 1 LAST LOCATION C5G52
J 0
(-6900 1950);
DISPLAY 0.617021 (-6900 1950);
PAINT AQUA (-6900 1950);
FORCEPROP 1 LASTPIN (-6950 1950) $PN 1
J 0
(-6940 1930);
DISPLAY 0.787234 (-6940 1930);
PAINT ORANGE (-6940 1930);
FORCEPROP 1 LASTPIN (-6950 1750) $PN 2
J 0
(-6940 1730);
DISPLAY 0.787234 (-6940 1730);
PAINT ORANGE (-6940 1730);
FORCEPROP 1 LAST PACK_TYPE 0603V
J 0
(-6900 1650);
DISPLAY 0.617021 (-6900 1650);
PAINT SKYBLUE (-6900 1650);
FORCEPROP 1 LAST MATERIAL X6S
J 0
(-6900 1750);
DISPLAY 0.617021 (-6900 1750);
PAINT SKYBLUE (-6900 1750);
FORCEPROP 1 LAST PART_NUMBER E15431-004
J 0
(-6900 1700);
DISPLAY 0.617021 (-6900 1700);
PAINT BLUE (-6900 1700);
FORCEPROP 0 LAST BOM_DS NOPOP
J 0
(-6894 1602);
DISPLAY 0.638298 (-6894 1602);
PAINT BROWN (-6894 1602);
DISPLAY BOTH (-6894 1602);
FORCEPROP 2 LAST SEC_TYPE 0603V
J 0
(-6900 2050);
DISPLAY 1.021277 (-6900 2050);
PAINT ORANGE (-6900 2050);
DISPLAY INVISIBLE (-6900 2050);
FORCEPROP 0 LAST SEC 1
J 0
(-6900 2000);
DISPLAY 0.680851 (-6900 2000);
PAINT MONO (-6900 2000);
DISPLAY INVISIBLE (-6900 2000);
FORCEPROP 2 LAST CDS_LIB dev_discrete
J 0
(-6950 1850);
PAINT MONO (-6950 1850);
DISPLAY INVISIBLE (-6950 1850);
FORCEPROP 1 LAST PATH I68
J 0
(-6900 2000);
DISPLAY 0.978723 (-6900 2000);
PAINT WHITE (-6900 2000);
DISPLAY INVISIBLE (-6900 2000);
FORCEPROP 0 LAST ROOM PVDDQ_KLM
J 0
(-6900 2050);
DISPLAY 1.021277 (-6900 2050);
PAINT ORANGE (-6900 2050);
DISPLAY INVISIBLE (-6900 2050);
FORCEADD CAP_A..1
(-7350 1850);
FORCEPROP 0 LAST GROUP PWR_MLCC_CAP
J 0
(-7281 1508);
DISPLAY 0.638298 (-7281 1508);
PAINT BROWN (-7281 1508);
DISPLAY BOTH (-7281 1508);
FORCEPROP 1 LAST VALUE 22.0UF
J 0
(-7300 1900);
DISPLAY 0.617021 (-7300 1900);
PAINT SKYBLUE (-7300 1900);
FORCEPROP 1 LAST VOLTAGE 4V
J 0
(-7300 1850);
DISPLAY 0.617021 (-7300 1850);
PAINT SKYBLUE (-7300 1850);
FORCEPROP 1 LAST TOLERANCE 20%
J 0
(-7300 1800);
DISPLAY 0.617021 (-7300 1800);
PAINT SKYBLUE (-7300 1800);
FORCEPROP 1 LAST LOCATION C5G51
J 0
(-7300 1950);
DISPLAY 0.617021 (-7300 1950);
PAINT AQUA (-7300 1950);
FORCEPROP 1 LAST PART_NUMBER E15431-004
J 0
(-7300 1700);
DISPLAY 0.617021 (-7300 1700);
PAINT BLUE (-7300 1700);
FORCEPROP 1 LAST MATERIAL X6S
J 0
(-7300 1750);
DISPLAY 0.617021 (-7300 1750);
PAINT SKYBLUE (-7300 1750);
FORCEPROP 1 LAST PACK_TYPE 0603V
J 0
(-7300 1650);
DISPLAY 0.617021 (-7300 1650);
PAINT SKYBLUE (-7300 1650);
FORCEPROP 1 LASTPIN (-7350 1750) $PN 2
J 0
(-7340 1730);
DISPLAY 0.787234 (-7340 1730);
PAINT ORANGE (-7340 1730);
FORCEPROP 1 LASTPIN (-7350 1950) $PN 1
J 0
(-7340 1930);
DISPLAY 0.787234 (-7340 1930);
PAINT ORANGE (-7340 1930);
FORCEPROP 0 LAST BOM_DS NOPOP
J 0
(-7294 1602);
DISPLAY 0.638298 (-7294 1602);
PAINT BROWN (-7294 1602);
DISPLAY BOTH (-7294 1602);
FORCEPROP 0 LAST ROOM PVDDQ_KLM
J 0
(-7300 2050);
DISPLAY 1.021277 (-7300 2050);
PAINT ORANGE (-7300 2050);
DISPLAY INVISIBLE (-7300 2050);
FORCEPROP 1 LAST PATH I69
J 0
(-7300 2000);
DISPLAY 0.978723 (-7300 2000);
PAINT WHITE (-7300 2000);
DISPLAY INVISIBLE (-7300 2000);
FORCEPROP 2 LAST CDS_LIB dev_discrete
J 0
(-7350 1850);
PAINT MONO (-7350 1850);
DISPLAY INVISIBLE (-7350 1850);
FORCEPROP 0 LAST SEC 1
J 0
(-7300 2000);
DISPLAY 0.680851 (-7300 2000);
PAINT MONO (-7300 2000);
DISPLAY INVISIBLE (-7300 2000);
FORCEPROP 2 LAST SEC_TYPE 0603V
J 0
(-7300 2050);
DISPLAY 1.021277 (-7300 2050);
PAINT ORANGE (-7300 2050);
DISPLAY INVISIBLE (-7300 2050);
FORCEADD GND..1
(-7750 2400);
FORCEPROP 3 LASTPIN (-7750 2450) SIG_NAME GND\g
J 0
(-7740 2460);
DISPLAY 0.659574 (-7740 2460);
PAINT MONO (-7740 2460);
DISPLAY INVISIBLE (-7740 2460);
FORCEPROP 1 LAST HDL_POWER GND
J 0
(-7750 2550);
DISPLAY 1.723404 (-7750 2550);
PAINT GREEN (-7750 2550);
DISPLAY INVISIBLE (-7750 2550);
FORCEPROP 1 LAST BODY_TYPE PLUMBING
J 0
(-7795 2357);
DISPLAY 0.340426 (-7795 2357);
PAINT GREEN (-7795 2357);
DISPLAY INVISIBLE (-7795 2357);
FORCEPROP 1 LAST PATH I7
J 0
(-7675 2400);
DISPLAY 0.872340 (-7675 2400);
PAINT AQUA (-7675 2400);
DISPLAY INVISIBLE (-7675 2400);
FORCEPROP 2 LAST CDS_LIB mstr_symbols
J 0
(-7750 2400);
PAINT MONO (-7750 2400);
DISPLAY INVISIBLE (-7750 2400);
FORCEPROP 1 LAST SIZE 1B
J 0
(-7675 2350);
DISPLAY 1.723404 (-7675 2350);
PAINT GREEN (-7675 2350);
DISPLAY INVISIBLE (-7675 2350);
FORCEPROP 2 LAST BOM_COST PROC_VRD_VCCIN_CPU0
J 0
(-8125 2475);
DISPLAY 1.446809 (-8125 2475);
PAINT MONO (-8125 2475);
DISPLAY INVISIBLE (-8125 2475);
FORCEPROP 2 LAST ROOM VDDQ_ABC_PWR_VR
J 0
(-8300 2475);
DISPLAY 1.936170 (-8300 2475);
PAINT ORANGE (-8300 2475);
DISPLAY INVISIBLE (-8300 2475);
FORCEPROP 1 LAST VOLTAGE 0
J 0
(-7750 2400);
PAINT SKYBLUE (-7750 2400);
DISPLAY INVISIBLE (-7750 2400);
FORCEADD CAP_A..1
(-7750 1850);
FORCEPROP 0 LAST GROUP PWR_MLCC_CAP
J 0
(-7702 1558);
DISPLAY 0.638298 (-7702 1558);
PAINT BROWN (-7702 1558);
DISPLAY BOTH (-7702 1558);
FORCEPROP 1 LAST PART_NUMBER E15431-004
J 0
(-7700 1700);
DISPLAY 0.617021 (-7700 1700);
PAINT BLUE (-7700 1700);
FORCEPROP 1 LAST PACK_TYPE 0603V
J 0
(-7700 1650);
DISPLAY 0.617021 (-7700 1650);
PAINT SKYBLUE (-7700 1650);
FORCEPROP 1 LAST MATERIAL X6S
J 0
(-7700 1750);
DISPLAY 0.617021 (-7700 1750);
PAINT SKYBLUE (-7700 1750);
FORCEPROP 1 LAST TOLERANCE 20%
J 0
(-7700 1800);
DISPLAY 0.617021 (-7700 1800);
PAINT SKYBLUE (-7700 1800);
FORCEPROP 1 LAST VALUE 22.0UF
J 0
(-7700 1900);
DISPLAY 0.617021 (-7700 1900);
PAINT SKYBLUE (-7700 1900);
FORCEPROP 1 LAST LOCATION C5G50
J 0
(-7700 1950);
DISPLAY 0.617021 (-7700 1950);
PAINT AQUA (-7700 1950);
FORCEPROP 1 LAST VOLTAGE 4V
J 0
(-7700 1850);
DISPLAY 0.617021 (-7700 1850);
PAINT SKYBLUE (-7700 1850);
FORCEPROP 1 LASTPIN (-7750 1750) $PN 2
J 0
(-7740 1730);
DISPLAY 0.787234 (-7740 1730);
PAINT ORANGE (-7740 1730);
FORCEPROP 1 LASTPIN (-7750 1950) $PN 1
J 0
(-7740 1930);
DISPLAY 0.787234 (-7740 1930);
PAINT ORANGE (-7740 1930);
FORCEPROP 0 LAST BOM_DS NOPOP
J 0
(-7694 1602);
DISPLAY 0.638298 (-7694 1602);
PAINT BROWN (-7694 1602);
DISPLAY BOTH (-7694 1602);
FORCEPROP 0 LAST ROOM PVDDQ_KLM
J 0
(-7700 2050);
DISPLAY 1.021277 (-7700 2050);
PAINT ORANGE (-7700 2050);
DISPLAY INVISIBLE (-7700 2050);
FORCEPROP 1 LAST PATH I70
J 0
(-7700 2000);
DISPLAY 0.978723 (-7700 2000);
PAINT WHITE (-7700 2000);
DISPLAY INVISIBLE (-7700 2000);
FORCEPROP 2 LAST CDS_LIB dev_discrete
J 0
(-7750 1850);
PAINT MONO (-7750 1850);
DISPLAY INVISIBLE (-7750 1850);
FORCEPROP 0 LAST SEC 1
J 0
(-7700 2000);
DISPLAY 0.680851 (-7700 2000);
PAINT MONO (-7700 2000);
DISPLAY INVISIBLE (-7700 2000);
FORCEPROP 2 LAST SEC_TYPE 0603V
J 0
(-7700 2050);
DISPLAY 1.021277 (-7700 2050);
PAINT ORANGE (-7700 2050);
DISPLAY INVISIBLE (-7700 2050);
FORCEADD CAP_A..1
(-600 2800);
FORCEPROP 1 LAST LOCATION C5G67
J 0
(-550 2900);
DISPLAY 0.617021 (-550 2900);
PAINT AQUA (-550 2900);
FORCEPROP 1 LAST VALUE 22.0UF
J 0
(-550 2850);
DISPLAY 0.617021 (-550 2850);
PAINT SKYBLUE (-550 2850);
FORCEPROP 1 LAST TOLERANCE 20%
J 0
(-550 2750);
DISPLAY 0.617021 (-550 2750);
PAINT SKYBLUE (-550 2750);
FORCEPROP 1 LAST VOLTAGE 4V
J 0
(-550 2800);
DISPLAY 0.617021 (-550 2800);
PAINT SKYBLUE (-550 2800);
FORCEPROP 1 LAST PART_NUMBER E15431-004
J 0
(-550 2650);
DISPLAY 0.617021 (-550 2650);
PAINT BLUE (-550 2650);
FORCEPROP 1 LAST MATERIAL X6S
J 0
(-550 2700);
DISPLAY 0.617021 (-550 2700);
PAINT SKYBLUE (-550 2700);
FORCEPROP 1 LAST PACK_TYPE 0603V
J 0
(-550 2600);
DISPLAY 0.617021 (-550 2600);
PAINT SKYBLUE (-550 2600);
FORCEPROP 1 LASTPIN (-600 2700) $PN 2
J 0
(-590 2680);
DISPLAY 0.787234 (-590 2680);
PAINT ORANGE (-590 2680);
FORCEPROP 1 LASTPIN (-600 2900) $PN 1
J 0
(-590 2880);
DISPLAY 0.787234 (-590 2880);
PAINT ORANGE (-590 2880);
FORCEPROP 0 LAST GROUP PWR_MLCC_CAP
J 0
(-551 2520);
DISPLAY 0.638298 (-551 2520);
PAINT BROWN (-551 2520);
DISPLAY BOTH (-551 2520);
FORCEPROP 0 LAST BOM_DS NOPOP
J 0
(-544 2552);
DISPLAY 0.638298 (-544 2552);
PAINT BROWN (-544 2552);
DISPLAY BOTH (-544 2552);
FORCEPROP 0 LAST ROOM PVDDQ_KLM
J 0
(-550 3000);
DISPLAY 1.021277 (-550 3000);
PAINT ORANGE (-550 3000);
DISPLAY INVISIBLE (-550 3000);
FORCEPROP 1 LAST PATH I71
J 0
(-550 2950);
DISPLAY 0.978723 (-550 2950);
PAINT WHITE (-550 2950);
DISPLAY INVISIBLE (-550 2950);
FORCEPROP 2 LAST CDS_LIB dev_discrete
J 0
(-600 2800);
PAINT MONO (-600 2800);
DISPLAY INVISIBLE (-600 2800);
FORCEPROP 0 LAST SEC 1
J 0
(-550 2950);
DISPLAY 0.680851 (-550 2950);
PAINT MONO (-550 2950);
DISPLAY INVISIBLE (-550 2950);
FORCEPROP 2 LAST SEC_TYPE 0603V
J 0
(-550 3000);
DISPLAY 1.021277 (-550 3000);
PAINT ORANGE (-550 3000);
DISPLAY INVISIBLE (-550 3000);
FORCEADD CAP_A..1
(-1000 2800);
FORCEPROP 1 LAST VOLTAGE 4V
J 0
(-950 2800);
DISPLAY 0.617021 (-950 2800);
PAINT SKYBLUE (-950 2800);
FORCEPROP 1 LAST VALUE 22.0UF
J 0
(-950 2850);
DISPLAY 0.617021 (-950 2850);
PAINT SKYBLUE (-950 2850);
FORCEPROP 1 LAST MATERIAL X6S
J 0
(-950 2700);
DISPLAY 0.617021 (-950 2700);
PAINT SKYBLUE (-950 2700);
FORCEPROP 1 LASTPIN (-1000 2900) $PN 1
J 0
(-990 2880);
DISPLAY 0.787234 (-990 2880);
PAINT ORANGE (-990 2880);
FORCEPROP 1 LASTPIN (-1000 2700) $PN 2
J 0
(-990 2680);
DISPLAY 0.787234 (-990 2680);
PAINT ORANGE (-990 2680);
FORCEPROP 1 LAST PACK_TYPE 0603V
J 0
(-950 2600);
DISPLAY 0.617021 (-950 2600);
PAINT SKYBLUE (-950 2600);
FORCEPROP 1 LAST LOCATION C5G66
J 0
(-950 2900);
DISPLAY 0.617021 (-950 2900);
PAINT AQUA (-950 2900);
FORCEPROP 1 LAST TOLERANCE 20%
J 0
(-950 2750);
DISPLAY 0.617021 (-950 2750);
PAINT SKYBLUE (-950 2750);
FORCEPROP 1 LAST PART_NUMBER E15431-004
J 0
(-950 2650);
DISPLAY 0.617021 (-950 2650);
PAINT BLUE (-950 2650);
FORCEPROP 0 LAST GROUP PWR_MLCC_CAP
J 0
(-951 2445);
DISPLAY 0.638298 (-951 2445);
PAINT BROWN (-951 2445);
DISPLAY BOTH (-951 2445);
FORCEPROP 0 LAST BOM_DS NOPOP
J 0
(-944 2552);
DISPLAY 0.638298 (-944 2552);
PAINT BROWN (-944 2552);
DISPLAY BOTH (-944 2552);
FORCEPROP 2 LAST SEC_TYPE 0603V
J 0
(-950 3000);
DISPLAY 1.021277 (-950 3000);
PAINT ORANGE (-950 3000);
DISPLAY INVISIBLE (-950 3000);
FORCEPROP 0 LAST SEC 1
J 0
(-950 2950);
DISPLAY 0.680851 (-950 2950);
PAINT MONO (-950 2950);
DISPLAY INVISIBLE (-950 2950);
FORCEPROP 2 LAST CDS_LIB dev_discrete
J 0
(-1000 2800);
PAINT MONO (-1000 2800);
DISPLAY INVISIBLE (-1000 2800);
FORCEPROP 1 LAST PATH I72
J 0
(-950 2950);
DISPLAY 0.978723 (-950 2950);
PAINT WHITE (-950 2950);
DISPLAY INVISIBLE (-950 2950);
FORCEPROP 0 LAST ROOM PVDDQ_KLM
J 0
(-950 3000);
DISPLAY 1.021277 (-950 3000);
PAINT ORANGE (-950 3000);
DISPLAY INVISIBLE (-950 3000);
FORCEADD CAP_A..1
(-1400 2800);
FORCEPROP 1 LAST LOCATION C5G65
J 0
(-1350 2900);
DISPLAY 0.617021 (-1350 2900);
PAINT AQUA (-1350 2900);
FORCEPROP 1 LAST VALUE 22.0UF
J 0
(-1350 2850);
DISPLAY 0.617021 (-1350 2850);
PAINT SKYBLUE (-1350 2850);
FORCEPROP 1 LAST PART_NUMBER E15431-004
J 0
(-1350 2650);
DISPLAY 0.617021 (-1350 2650);
PAINT BLUE (-1350 2650);
FORCEPROP 1 LAST MATERIAL X6S
J 0
(-1350 2700);
DISPLAY 0.617021 (-1350 2700);
PAINT SKYBLUE (-1350 2700);
FORCEPROP 1 LAST PACK_TYPE 0603V
J 0
(-1350 2600);
DISPLAY 0.617021 (-1350 2600);
PAINT SKYBLUE (-1350 2600);
FORCEPROP 1 LASTPIN (-1400 2700) $PN 2
J 0
(-1390 2680);
DISPLAY 0.787234 (-1390 2680);
PAINT ORANGE (-1390 2680);
FORCEPROP 1 LASTPIN (-1400 2900) $PN 1
J 0
(-1390 2880);
DISPLAY 0.787234 (-1390 2880);
PAINT ORANGE (-1390 2880);
FORCEPROP 1 LAST VOLTAGE 4V
J 0
(-1350 2800);
DISPLAY 0.617021 (-1350 2800);
PAINT SKYBLUE (-1350 2800);
FORCEPROP 1 LAST TOLERANCE 20%
J 0
(-1350 2750);
DISPLAY 0.617021 (-1350 2750);
PAINT SKYBLUE (-1350 2750);
FORCEPROP 0 LAST GROUP PWR_MLCC_CAP
J 0
(-1351 2495);
DISPLAY 0.638298 (-1351 2495);
PAINT BROWN (-1351 2495);
DISPLAY BOTH (-1351 2495);
FORCEPROP 0 LAST BOM_DS NOPOP
J 0
(-1344 2552);
DISPLAY 0.638298 (-1344 2552);
PAINT BROWN (-1344 2552);
DISPLAY BOTH (-1344 2552);
FORCEPROP 0 LAST ROOM PVDDQ_KLM
J 0
(-1350 3000);
DISPLAY 1.021277 (-1350 3000);
PAINT ORANGE (-1350 3000);
DISPLAY INVISIBLE (-1350 3000);
FORCEPROP 1 LAST PATH I73
J 0
(-1350 2950);
DISPLAY 0.978723 (-1350 2950);
PAINT WHITE (-1350 2950);
DISPLAY INVISIBLE (-1350 2950);
FORCEPROP 2 LAST CDS_LIB dev_discrete
J 0
(-1400 2800);
PAINT MONO (-1400 2800);
DISPLAY INVISIBLE (-1400 2800);
FORCEPROP 0 LAST SEC 1
J 0
(-1350 2950);
DISPLAY 0.680851 (-1350 2950);
PAINT MONO (-1350 2950);
DISPLAY INVISIBLE (-1350 2950);
FORCEPROP 2 LAST SEC_TYPE 0603V
J 0
(-1350 3000);
DISPLAY 1.021277 (-1350 3000);
PAINT ORANGE (-1350 3000);
DISPLAY INVISIBLE (-1350 3000);
FORCEADD CAP_A..1
(-1800 2800);
FORCEPROP 1 LASTPIN (-1800 2900) $PN 1
J 0
(-1790 2880);
DISPLAY 0.787234 (-1790 2880);
PAINT ORANGE (-1790 2880);
FORCEPROP 1 LASTPIN (-1800 2700) $PN 2
J 0
(-1790 2680);
DISPLAY 0.787234 (-1790 2680);
PAINT ORANGE (-1790 2680);
FORCEPROP 1 LAST PACK_TYPE 0603V
J 0
(-1750 2600);
DISPLAY 0.617021 (-1750 2600);
PAINT SKYBLUE (-1750 2600);
FORCEPROP 1 LAST PART_NUMBER E15431-004
J 0
(-1750 2650);
DISPLAY 0.617021 (-1750 2650);
PAINT BLUE (-1750 2650);
FORCEPROP 1 LAST LOCATION C5G64
J 0
(-1750 2900);
DISPLAY 0.617021 (-1750 2900);
PAINT AQUA (-1750 2900);
FORCEPROP 1 LAST VALUE 22.0UF
J 0
(-1750 2850);
DISPLAY 0.617021 (-1750 2850);
PAINT SKYBLUE (-1750 2850);
FORCEPROP 1 LAST MATERIAL X6S
J 0
(-1750 2700);
DISPLAY 0.617021 (-1750 2700);
PAINT SKYBLUE (-1750 2700);
FORCEPROP 1 LAST VOLTAGE 4V
J 0
(-1750 2800);
DISPLAY 0.617021 (-1750 2800);
PAINT SKYBLUE (-1750 2800);
FORCEPROP 1 LAST TOLERANCE 20%
J 0
(-1750 2750);
DISPLAY 0.617021 (-1750 2750);
PAINT SKYBLUE (-1750 2750);
FORCEPROP 0 LAST GROUP PWR_MLCC_CAP
J 0
(-1751 2445);
DISPLAY 0.638298 (-1751 2445);
PAINT BROWN (-1751 2445);
DISPLAY BOTH (-1751 2445);
FORCEPROP 0 LAST BOM_DS NOPOP
J 0
(-1744 2552);
DISPLAY 0.638298 (-1744 2552);
PAINT BROWN (-1744 2552);
DISPLAY BOTH (-1744 2552);
FORCEPROP 2 LAST SEC_TYPE 0603V
J 0
(-1750 3000);
DISPLAY 1.021277 (-1750 3000);
PAINT ORANGE (-1750 3000);
DISPLAY INVISIBLE (-1750 3000);
FORCEPROP 0 LAST SEC 1
J 0
(-1750 2950);
DISPLAY 0.680851 (-1750 2950);
PAINT MONO (-1750 2950);
DISPLAY INVISIBLE (-1750 2950);
FORCEPROP 2 LAST CDS_LIB dev_discrete
J 0
(-1800 2800);
PAINT MONO (-1800 2800);
DISPLAY INVISIBLE (-1800 2800);
FORCEPROP 1 LAST PATH I74
J 0
(-1750 2950);
DISPLAY 0.978723 (-1750 2950);
PAINT WHITE (-1750 2950);
DISPLAY INVISIBLE (-1750 2950);
FORCEPROP 0 LAST ROOM PVDDQ_KLM
J 0
(-1750 3000);
DISPLAY 1.021277 (-1750 3000);
PAINT ORANGE (-1750 3000);
DISPLAY INVISIBLE (-1750 3000);
FORCEADD CAP_A..1
(-2200 2800);
FORCEPROP 1 LAST VALUE 22.0UF
J 0
(-2150 2850);
DISPLAY 0.617021 (-2150 2850);
PAINT SKYBLUE (-2150 2850);
FORCEPROP 1 LASTPIN (-2200 2700) $PN 2
J 0
(-2190 2680);
DISPLAY 0.787234 (-2190 2680);
PAINT ORANGE (-2190 2680);
FORCEPROP 1 LASTPIN (-2200 2900) $PN 1
J 0
(-2190 2880);
DISPLAY 0.787234 (-2190 2880);
PAINT ORANGE (-2190 2880);
FORCEPROP 1 LAST TOLERANCE 20%
J 0
(-2150 2750);
DISPLAY 0.617021 (-2150 2750);
PAINT SKYBLUE (-2150 2750);
FORCEPROP 1 LAST VOLTAGE 4V
J 0
(-2150 2800);
DISPLAY 0.617021 (-2150 2800);
PAINT SKYBLUE (-2150 2800);
FORCEPROP 1 LAST PACK_TYPE 0603V
J 0
(-2150 2600);
DISPLAY 0.617021 (-2150 2600);
PAINT SKYBLUE (-2150 2600);
FORCEPROP 1 LAST PART_NUMBER E15431-004
J 0
(-2150 2650);
DISPLAY 0.617021 (-2150 2650);
PAINT BLUE (-2150 2650);
FORCEPROP 1 LAST MATERIAL X6S
J 0
(-2150 2700);
DISPLAY 0.617021 (-2150 2700);
PAINT SKYBLUE (-2150 2700);
FORCEPROP 1 LAST LOCATION C5G63
J 0
(-2150 2900);
DISPLAY 0.617021 (-2150 2900);
PAINT AQUA (-2150 2900);
FORCEPROP 0 LAST GROUP PWR_MLCC_CAP
J 0
(-2151 2495);
DISPLAY 0.638298 (-2151 2495);
PAINT BROWN (-2151 2495);
DISPLAY BOTH (-2151 2495);
FORCEPROP 0 LAST BOM_DS NOPOP
J 0
(-2144 2552);
DISPLAY 0.638298 (-2144 2552);
PAINT BROWN (-2144 2552);
DISPLAY BOTH (-2144 2552);
FORCEPROP 0 LAST ROOM PVDDQ_KLM
J 0
(-2150 3000);
DISPLAY 1.021277 (-2150 3000);
PAINT ORANGE (-2150 3000);
DISPLAY INVISIBLE (-2150 3000);
FORCEPROP 1 LAST PATH I75
J 0
(-2150 2950);
DISPLAY 0.978723 (-2150 2950);
PAINT WHITE (-2150 2950);
DISPLAY INVISIBLE (-2150 2950);
FORCEPROP 2 LAST CDS_LIB dev_discrete
J 0
(-2200 2800);
PAINT MONO (-2200 2800);
DISPLAY INVISIBLE (-2200 2800);
FORCEPROP 0 LAST SEC 1
J 0
(-2150 2950);
DISPLAY 0.680851 (-2150 2950);
PAINT MONO (-2150 2950);
DISPLAY INVISIBLE (-2150 2950);
FORCEPROP 2 LAST SEC_TYPE 0603V
J 0
(-2150 3000);
DISPLAY 1.021277 (-2150 3000);
PAINT ORANGE (-2150 3000);
DISPLAY INVISIBLE (-2150 3000);
FORCEADD CAP_A..1
(-2600 2800);
FORCEPROP 1 LASTPIN (-2600 2900) $PN 1
J 0
(-2590 2880);
DISPLAY 0.787234 (-2590 2880);
PAINT ORANGE (-2590 2880);
FORCEPROP 1 LASTPIN (-2600 2700) $PN 2
J 0
(-2590 2680);
DISPLAY 0.787234 (-2590 2680);
PAINT ORANGE (-2590 2680);
FORCEPROP 1 LAST VOLTAGE 4V
J 0
(-2550 2800);
DISPLAY 0.617021 (-2550 2800);
PAINT SKYBLUE (-2550 2800);
FORCEPROP 1 LAST PACK_TYPE 0603V
J 0
(-2550 2600);
DISPLAY 0.617021 (-2550 2600);
PAINT SKYBLUE (-2550 2600);
FORCEPROP 1 LAST PART_NUMBER E15431-004
J 0
(-2550 2650);
DISPLAY 0.617021 (-2550 2650);
PAINT BLUE (-2550 2650);
FORCEPROP 1 LAST MATERIAL X6S
J 0
(-2550 2700);
DISPLAY 0.617021 (-2550 2700);
PAINT SKYBLUE (-2550 2700);
FORCEPROP 1 LAST TOLERANCE 20%
J 0
(-2550 2750);
DISPLAY 0.617021 (-2550 2750);
PAINT SKYBLUE (-2550 2750);
FORCEPROP 0 LAST GROUP PWR_MLCC_CAP
J 0
(-2551 2445);
DISPLAY 0.638298 (-2551 2445);
PAINT BROWN (-2551 2445);
DISPLAY BOTH (-2551 2445);
FORCEPROP 1 LAST VALUE 22.0UF
J 0
(-2550 2850);
DISPLAY 0.617021 (-2550 2850);
PAINT SKYBLUE (-2550 2850);
FORCEPROP 1 LAST LOCATION C5G62
J 0
(-2550 2900);
DISPLAY 0.617021 (-2550 2900);
PAINT AQUA (-2550 2900);
FORCEPROP 0 LAST BOM_DS NOPOP
J 0
(-2544 2552);
DISPLAY 0.638298 (-2544 2552);
PAINT BROWN (-2544 2552);
DISPLAY BOTH (-2544 2552);
FORCEPROP 2 LAST SEC_TYPE 0603V
J 0
(-2550 3000);
DISPLAY 1.021277 (-2550 3000);
PAINT ORANGE (-2550 3000);
DISPLAY INVISIBLE (-2550 3000);
FORCEPROP 0 LAST SEC 1
J 0
(-2550 2950);
DISPLAY 0.680851 (-2550 2950);
PAINT MONO (-2550 2950);
DISPLAY INVISIBLE (-2550 2950);
FORCEPROP 2 LAST CDS_LIB dev_discrete
J 0
(-2600 2800);
PAINT MONO (-2600 2800);
DISPLAY INVISIBLE (-2600 2800);
FORCEPROP 1 LAST PATH I76
J 0
(-2550 2950);
DISPLAY 0.978723 (-2550 2950);
PAINT WHITE (-2550 2950);
DISPLAY INVISIBLE (-2550 2950);
FORCEPROP 0 LAST ROOM PVDDQ_KLM
J 0
(-2550 3000);
DISPLAY 1.021277 (-2550 3000);
PAINT ORANGE (-2550 3000);
DISPLAY INVISIBLE (-2550 3000);
FORCEADD CAP_A..1
(-3000 2800);
FORCEPROP 1 LASTPIN (-3000 2700) $PN 2
J 0
(-2990 2680);
DISPLAY 0.787234 (-2990 2680);
PAINT ORANGE (-2990 2680);
FORCEPROP 1 LASTPIN (-3000 2900) $PN 1
J 0
(-2990 2880);
DISPLAY 0.787234 (-2990 2880);
PAINT ORANGE (-2990 2880);
FORCEPROP 1 LAST PACK_TYPE 0603V
J 0
(-2950 2600);
DISPLAY 0.617021 (-2950 2600);
PAINT SKYBLUE (-2950 2600);
FORCEPROP 1 LAST VOLTAGE 4V
J 0
(-2950 2800);
DISPLAY 0.617021 (-2950 2800);
PAINT SKYBLUE (-2950 2800);
FORCEPROP 1 LAST VALUE 22.0UF
J 0
(-2950 2850);
DISPLAY 0.617021 (-2950 2850);
PAINT SKYBLUE (-2950 2850);
FORCEPROP 1 LAST LOCATION C5G61
J 0
(-2950 2900);
DISPLAY 0.617021 (-2950 2900);
PAINT AQUA (-2950 2900);
FORCEPROP 1 LAST TOLERANCE 20%
J 0
(-2950 2750);
DISPLAY 0.617021 (-2950 2750);
PAINT SKYBLUE (-2950 2750);
FORCEPROP 0 LAST GROUP PWR_MLCC_CAP
J 0
(-2951 2520);
DISPLAY 0.638298 (-2951 2520);
PAINT BROWN (-2951 2520);
DISPLAY BOTH (-2951 2520);
FORCEPROP 1 LAST PART_NUMBER E15431-004
J 0
(-2950 2650);
DISPLAY 0.617021 (-2950 2650);
PAINT BLUE (-2950 2650);
FORCEPROP 1 LAST MATERIAL X6S
J 0
(-2950 2700);
DISPLAY 0.617021 (-2950 2700);
PAINT SKYBLUE (-2950 2700);
FORCEPROP 0 LAST BOM_DS NOPOP
J 0
(-2944 2552);
DISPLAY 0.638298 (-2944 2552);
PAINT BROWN (-2944 2552);
DISPLAY BOTH (-2944 2552);
FORCEPROP 2 LAST CDS_LIB dev_discrete
J 0
(-3000 2800);
PAINT MONO (-3000 2800);
DISPLAY INVISIBLE (-3000 2800);
FORCEPROP 1 LAST PATH I77
J 0
(-2950 2950);
DISPLAY 0.978723 (-2950 2950);
PAINT WHITE (-2950 2950);
DISPLAY INVISIBLE (-2950 2950);
FORCEPROP 0 LAST ROOM PVDDQ_KLM
J 0
(-2950 3000);
DISPLAY 1.021277 (-2950 3000);
PAINT ORANGE (-2950 3000);
DISPLAY INVISIBLE (-2950 3000);
FORCEPROP 0 LAST SEC 1
J 0
(-2950 2950);
DISPLAY 0.680851 (-2950 2950);
PAINT MONO (-2950 2950);
DISPLAY INVISIBLE (-2950 2950);
FORCEPROP 2 LAST SEC_TYPE 0603V
J 0
(-2950 3000);
DISPLAY 1.021277 (-2950 3000);
PAINT ORANGE (-2950 3000);
DISPLAY INVISIBLE (-2950 3000);
FORCEADD CAP_A..1
(-3400 2800);
FORCEPROP 1 LASTPIN (-3400 2900) $PN 1
J 0
(-3390 2880);
DISPLAY 0.787234 (-3390 2880);
PAINT ORANGE (-3390 2880);
FORCEPROP 1 LASTPIN (-3400 2700) $PN 2
J 0
(-3390 2680);
DISPLAY 0.787234 (-3390 2680);
PAINT ORANGE (-3390 2680);
FORCEPROP 1 LAST MATERIAL X6S
J 0
(-3350 2700);
DISPLAY 0.617021 (-3350 2700);
PAINT SKYBLUE (-3350 2700);
FORCEPROP 1 LAST PACK_TYPE 0603V
J 0
(-3350 2600);
DISPLAY 0.617021 (-3350 2600);
PAINT SKYBLUE (-3350 2600);
FORCEPROP 1 LAST PART_NUMBER E15431-004
J 0
(-3350 2650);
DISPLAY 0.617021 (-3350 2650);
PAINT BLUE (-3350 2650);
FORCEPROP 0 LAST GROUP PWR_MLCC_CAP
J 0
(-3351 2445);
DISPLAY 0.638298 (-3351 2445);
PAINT BROWN (-3351 2445);
DISPLAY BOTH (-3351 2445);
FORCEPROP 1 LAST TOLERANCE 20%
J 0
(-3350 2750);
DISPLAY 0.617021 (-3350 2750);
PAINT SKYBLUE (-3350 2750);
FORCEPROP 1 LAST VOLTAGE 4V
J 0
(-3350 2800);
DISPLAY 0.617021 (-3350 2800);
PAINT SKYBLUE (-3350 2800);
FORCEPROP 1 LAST VALUE 22.0UF
J 0
(-3350 2850);
DISPLAY 0.617021 (-3350 2850);
PAINT SKYBLUE (-3350 2850);
FORCEPROP 1 LAST LOCATION C5G60
J 0
(-3350 2900);
DISPLAY 0.617021 (-3350 2900);
PAINT AQUA (-3350 2900);
FORCEPROP 0 LAST BOM_DS NOPOP
J 0
(-3344 2552);
DISPLAY 0.638298 (-3344 2552);
PAINT BROWN (-3344 2552);
DISPLAY BOTH (-3344 2552);
FORCEPROP 2 LAST SEC_TYPE 0603V
J 0
(-3350 3000);
DISPLAY 1.021277 (-3350 3000);
PAINT ORANGE (-3350 3000);
DISPLAY INVISIBLE (-3350 3000);
FORCEPROP 0 LAST SEC 1
J 0
(-3350 2950);
DISPLAY 0.680851 (-3350 2950);
PAINT MONO (-3350 2950);
DISPLAY INVISIBLE (-3350 2950);
FORCEPROP 0 LAST ROOM PVDDQ_KLM
J 0
(-3350 3000);
DISPLAY 1.021277 (-3350 3000);
PAINT ORANGE (-3350 3000);
DISPLAY INVISIBLE (-3350 3000);
FORCEPROP 1 LAST PATH I78
J 0
(-3350 2950);
DISPLAY 0.978723 (-3350 2950);
PAINT WHITE (-3350 2950);
DISPLAY INVISIBLE (-3350 2950);
FORCEPROP 2 LAST CDS_LIB dev_discrete
J 0
(-3400 2800);
PAINT MONO (-3400 2800);
DISPLAY INVISIBLE (-3400 2800);
FORCEADD CAP_A..1
(-3800 2800);
FORCEPROP 1 LASTPIN (-3800 2700) $PN 2
J 0
(-3790 2680);
DISPLAY 0.787234 (-3790 2680);
PAINT ORANGE (-3790 2680);
FORCEPROP 1 LAST VOLTAGE 4V
J 0
(-3750 2800);
DISPLAY 0.617021 (-3750 2800);
PAINT SKYBLUE (-3750 2800);
FORCEPROP 1 LAST VALUE 22.0UF
J 0
(-3750 2850);
DISPLAY 0.617021 (-3750 2850);
PAINT SKYBLUE (-3750 2850);
FORCEPROP 1 LAST MATERIAL X6S
J 0
(-3750 2700);
DISPLAY 0.617021 (-3750 2700);
PAINT SKYBLUE (-3750 2700);
FORCEPROP 1 LAST TOLERANCE 20%
J 0
(-3750 2750);
DISPLAY 0.617021 (-3750 2750);
PAINT SKYBLUE (-3750 2750);
FORCEPROP 1 LASTPIN (-3800 2900) $PN 1
J 0
(-3790 2880);
DISPLAY 0.787234 (-3790 2880);
PAINT ORANGE (-3790 2880);
FORCEPROP 1 LAST LOCATION C5G59
J 0
(-3750 2900);
DISPLAY 0.617021 (-3750 2900);
PAINT AQUA (-3750 2900);
FORCEPROP 0 LAST GROUP PWR_MLCC_CAP
J 0
(-3751 2520);
DISPLAY 0.638298 (-3751 2520);
PAINT BROWN (-3751 2520);
DISPLAY BOTH (-3751 2520);
FORCEPROP 1 LAST PACK_TYPE 0603V
J 0
(-3750 2600);
DISPLAY 0.617021 (-3750 2600);
PAINT SKYBLUE (-3750 2600);
FORCEPROP 1 LAST PART_NUMBER E15431-004
J 0
(-3750 2650);
DISPLAY 0.617021 (-3750 2650);
PAINT BLUE (-3750 2650);
FORCEPROP 0 LAST BOM_DS NOPOP
J 0
(-3744 2552);
DISPLAY 0.638298 (-3744 2552);
PAINT BROWN (-3744 2552);
DISPLAY BOTH (-3744 2552);
FORCEPROP 2 LAST CDS_LIB dev_discrete
J 0
(-3800 2800);
PAINT MONO (-3800 2800);
DISPLAY INVISIBLE (-3800 2800);
FORCEPROP 1 LAST PATH I79
J 0
(-3750 2950);
DISPLAY 0.978723 (-3750 2950);
PAINT WHITE (-3750 2950);
DISPLAY INVISIBLE (-3750 2950);
FORCEPROP 0 LAST ROOM PVDDQ_KLM
J 0
(-3750 3000);
DISPLAY 1.021277 (-3750 3000);
PAINT ORANGE (-3750 3000);
DISPLAY INVISIBLE (-3750 3000);
FORCEPROP 0 LAST SEC 1
J 0
(-3750 2950);
DISPLAY 0.680851 (-3750 2950);
PAINT MONO (-3750 2950);
DISPLAY INVISIBLE (-3750 2950);
FORCEPROP 2 LAST SEC_TYPE 0603V
J 0
(-3750 3000);
DISPLAY 1.021277 (-3750 3000);
PAINT ORANGE (-3750 3000);
DISPLAY INVISIBLE (-3750 3000);
FORCEADD CAP_A..1
(-600 1850);
FORCEPROP 1 LASTPIN (-600 1950) $PN 1
J 0
(-590 1930);
DISPLAY 0.787234 (-590 1930);
PAINT ORANGE (-590 1930);
FORCEPROP 1 LASTPIN (-600 1750) $PN 2
J 0
(-590 1730);
DISPLAY 0.787234 (-590 1730);
PAINT ORANGE (-590 1730);
FORCEPROP 1 LAST VOLTAGE 4V
J 0
(-550 1850);
DISPLAY 0.617021 (-550 1850);
PAINT SKYBLUE (-550 1850);
FORCEPROP 1 LAST TOLERANCE 20%
J 0
(-550 1800);
DISPLAY 0.617021 (-550 1800);
PAINT SKYBLUE (-550 1800);
FORCEPROP 1 LAST MATERIAL X6S
J 0
(-550 1750);
DISPLAY 0.617021 (-550 1750);
PAINT SKYBLUE (-550 1750);
FORCEPROP 1 LAST LOCATION C5G76
J 0
(-550 1950);
DISPLAY 0.617021 (-550 1950);
PAINT AQUA (-550 1950);
FORCEPROP 1 LAST VALUE 22.0UF
J 0
(-550 1900);
DISPLAY 0.617021 (-550 1900);
PAINT SKYBLUE (-550 1900);
FORCEPROP 0 LAST GROUP PWR_MLCC_CAP
J 0
(-551 1545);
DISPLAY 0.638298 (-551 1545);
PAINT BROWN (-551 1545);
DISPLAY BOTH (-551 1545);
FORCEPROP 1 LAST PACK_TYPE 0603V
J 0
(-550 1650);
DISPLAY 0.617021 (-550 1650);
PAINT SKYBLUE (-550 1650);
FORCEPROP 1 LAST PART_NUMBER E15431-004
J 0
(-550 1700);
DISPLAY 0.617021 (-550 1700);
PAINT BLUE (-550 1700);
FORCEPROP 0 LAST BOM_DS NOPOP
J 0
(-544 1602);
DISPLAY 0.638298 (-544 1602);
PAINT BROWN (-544 1602);
DISPLAY BOTH (-544 1602);
FORCEPROP 2 LAST SEC_TYPE 0603V
J 0
(-550 2050);
DISPLAY 1.021277 (-550 2050);
PAINT ORANGE (-550 2050);
DISPLAY INVISIBLE (-550 2050);
FORCEPROP 0 LAST SEC 1
J 0
(-550 2000);
DISPLAY 0.680851 (-550 2000);
PAINT MONO (-550 2000);
DISPLAY INVISIBLE (-550 2000);
FORCEPROP 0 LAST ROOM PVDDQ_KLM
J 0
(-550 2050);
DISPLAY 1.021277 (-550 2050);
PAINT ORANGE (-550 2050);
DISPLAY INVISIBLE (-550 2050);
FORCEPROP 1 LAST PATH I80
J 0
(-550 2000);
DISPLAY 0.978723 (-550 2000);
PAINT WHITE (-550 2000);
DISPLAY INVISIBLE (-550 2000);
FORCEPROP 2 LAST CDS_LIB dev_discrete
J 0
(-600 1850);
PAINT MONO (-600 1850);
DISPLAY INVISIBLE (-600 1850);
FORCEADD CAP_A..1
(-1000 1850);
FORCEPROP 1 LAST PACK_TYPE 0603V
J 0
(-950 1650);
DISPLAY 0.617021 (-950 1650);
PAINT SKYBLUE (-950 1650);
FORCEPROP 1 LAST LOCATION C5G75
J 0
(-950 1950);
DISPLAY 0.617021 (-950 1950);
PAINT AQUA (-950 1950);
FORCEPROP 1 LAST VALUE 22.0UF
J 0
(-950 1900);
DISPLAY 0.617021 (-950 1900);
PAINT SKYBLUE (-950 1900);
FORCEPROP 1 LAST PART_NUMBER E15431-004
J 0
(-950 1700);
DISPLAY 0.617021 (-950 1700);
PAINT BLUE (-950 1700);
FORCEPROP 1 LAST MATERIAL X6S
J 0
(-950 1750);
DISPLAY 0.617021 (-950 1750);
PAINT SKYBLUE (-950 1750);
FORCEPROP 1 LAST TOLERANCE 20%
J 0
(-950 1800);
DISPLAY 0.617021 (-950 1800);
PAINT SKYBLUE (-950 1800);
FORCEPROP 1 LAST VOLTAGE 4V
J 0
(-950 1850);
DISPLAY 0.617021 (-950 1850);
PAINT SKYBLUE (-950 1850);
FORCEPROP 1 LASTPIN (-1000 1750) $PN 2
J 0
(-990 1730);
DISPLAY 0.787234 (-990 1730);
PAINT ORANGE (-990 1730);
FORCEPROP 1 LASTPIN (-1000 1950) $PN 1
J 0
(-990 1930);
DISPLAY 0.787234 (-990 1930);
PAINT ORANGE (-990 1930);
FORCEPROP 0 LAST GROUP PWR_MLCC_CAP
J 0
(-951 1495);
DISPLAY 0.638298 (-951 1495);
PAINT BROWN (-951 1495);
DISPLAY BOTH (-951 1495);
FORCEPROP 0 LAST BOM_DS NOPOP
J 0
(-944 1602);
DISPLAY 0.638298 (-944 1602);
PAINT BROWN (-944 1602);
DISPLAY BOTH (-944 1602);
FORCEPROP 2 LAST CDS_LIB dev_discrete
J 0
(-1000 1850);
PAINT MONO (-1000 1850);
DISPLAY INVISIBLE (-1000 1850);
FORCEPROP 1 LAST PATH I81
J 0
(-950 2000);
DISPLAY 0.978723 (-950 2000);
PAINT WHITE (-950 2000);
DISPLAY INVISIBLE (-950 2000);
FORCEPROP 0 LAST ROOM PVDDQ_KLM
J 0
(-950 2050);
DISPLAY 1.021277 (-950 2050);
PAINT ORANGE (-950 2050);
DISPLAY INVISIBLE (-950 2050);
FORCEPROP 0 LAST SEC 1
J 0
(-950 2000);
DISPLAY 0.680851 (-950 2000);
PAINT MONO (-950 2000);
DISPLAY INVISIBLE (-950 2000);
FORCEPROP 2 LAST SEC_TYPE 0603V
J 0
(-950 2050);
DISPLAY 1.021277 (-950 2050);
PAINT ORANGE (-950 2050);
DISPLAY INVISIBLE (-950 2050);
FORCEADD CAP_A..1
(-1400 1850);
FORCEPROP 1 LASTPIN (-1400 1950) $PN 1
J 0
(-1390 1930);
DISPLAY 0.787234 (-1390 1930);
PAINT ORANGE (-1390 1930);
FORCEPROP 1 LASTPIN (-1400 1750) $PN 2
J 0
(-1390 1730);
DISPLAY 0.787234 (-1390 1730);
PAINT ORANGE (-1390 1730);
FORCEPROP 1 LAST PACK_TYPE 0603V
J 0
(-1350 1650);
DISPLAY 0.617021 (-1350 1650);
PAINT SKYBLUE (-1350 1650);
FORCEPROP 1 LAST VALUE 22.0UF
J 0
(-1350 1900);
DISPLAY 0.617021 (-1350 1900);
PAINT SKYBLUE (-1350 1900);
FORCEPROP 1 LAST TOLERANCE 20%
J 0
(-1350 1800);
DISPLAY 0.617021 (-1350 1800);
PAINT SKYBLUE (-1350 1800);
FORCEPROP 1 LAST VOLTAGE 4V
J 0
(-1350 1850);
DISPLAY 0.617021 (-1350 1850);
PAINT SKYBLUE (-1350 1850);
FORCEPROP 1 LAST MATERIAL X6S
J 0
(-1350 1750);
DISPLAY 0.617021 (-1350 1750);
PAINT SKYBLUE (-1350 1750);
FORCEPROP 1 LAST LOCATION C5G74
J 0
(-1350 1950);
DISPLAY 0.617021 (-1350 1950);
PAINT AQUA (-1350 1950);
FORCEPROP 1 LAST PART_NUMBER E15431-004
J 0
(-1350 1700);
DISPLAY 0.617021 (-1350 1700);
PAINT BLUE (-1350 1700);
FORCEPROP 0 LAST GROUP PWR_MLCC_CAP
J 0
(-1351 1570);
DISPLAY 0.638298 (-1351 1570);
PAINT BROWN (-1351 1570);
DISPLAY BOTH (-1351 1570);
FORCEPROP 0 LAST BOM_DS NOPOP
J 0
(-1344 1602);
DISPLAY 0.638298 (-1344 1602);
PAINT BROWN (-1344 1602);
DISPLAY BOTH (-1344 1602);
FORCEPROP 2 LAST SEC_TYPE 0603V
J 0
(-1350 2050);
DISPLAY 1.021277 (-1350 2050);
PAINT ORANGE (-1350 2050);
DISPLAY INVISIBLE (-1350 2050);
FORCEPROP 0 LAST SEC 1
J 0
(-1350 2000);
DISPLAY 0.680851 (-1350 2000);
PAINT MONO (-1350 2000);
DISPLAY INVISIBLE (-1350 2000);
FORCEPROP 0 LAST ROOM PVDDQ_KLM
J 0
(-1350 2050);
DISPLAY 1.021277 (-1350 2050);
PAINT ORANGE (-1350 2050);
DISPLAY INVISIBLE (-1350 2050);
FORCEPROP 1 LAST PATH I82
J 0
(-1350 2000);
DISPLAY 0.978723 (-1350 2000);
PAINT WHITE (-1350 2000);
DISPLAY INVISIBLE (-1350 2000);
FORCEPROP 2 LAST CDS_LIB dev_discrete
J 0
(-1400 1850);
PAINT MONO (-1400 1850);
DISPLAY INVISIBLE (-1400 1850);
FORCEADD CAP_A..1
(-1800 1850);
FORCEPROP 1 LAST PART_NUMBER E15431-004
J 0
(-1750 1700);
DISPLAY 0.617021 (-1750 1700);
PAINT BLUE (-1750 1700);
FORCEPROP 1 LAST LOCATION C5G73
J 0
(-1750 1950);
DISPLAY 0.617021 (-1750 1950);
PAINT AQUA (-1750 1950);
FORCEPROP 1 LAST MATERIAL X6S
J 0
(-1750 1750);
DISPLAY 0.617021 (-1750 1750);
PAINT SKYBLUE (-1750 1750);
FORCEPROP 1 LAST VOLTAGE 4V
J 0
(-1750 1850);
DISPLAY 0.617021 (-1750 1850);
PAINT SKYBLUE (-1750 1850);
FORCEPROP 1 LAST TOLERANCE 20%
J 0
(-1750 1800);
DISPLAY 0.617021 (-1750 1800);
PAINT SKYBLUE (-1750 1800);
FORCEPROP 1 LAST PACK_TYPE 0603V
J 0
(-1750 1650);
DISPLAY 0.617021 (-1750 1650);
PAINT SKYBLUE (-1750 1650);
FORCEPROP 1 LASTPIN (-1800 1750) $PN 2
J 0
(-1790 1730);
DISPLAY 0.787234 (-1790 1730);
PAINT ORANGE (-1790 1730);
FORCEPROP 1 LASTPIN (-1800 1950) $PN 1
J 0
(-1790 1930);
DISPLAY 0.787234 (-1790 1930);
PAINT ORANGE (-1790 1930);
FORCEPROP 1 LAST VALUE 22.0UF
J 0
(-1750 1900);
DISPLAY 0.617021 (-1750 1900);
PAINT SKYBLUE (-1750 1900);
FORCEPROP 0 LAST GROUP PWR_MLCC_CAP
J 0
(-1751 1520);
DISPLAY 0.638298 (-1751 1520);
PAINT BROWN (-1751 1520);
DISPLAY BOTH (-1751 1520);
FORCEPROP 0 LAST BOM_DS NOPOP
J 0
(-1769 1602);
DISPLAY 0.638298 (-1769 1602);
PAINT BROWN (-1769 1602);
DISPLAY BOTH (-1769 1602);
FORCEPROP 2 LAST CDS_LIB dev_discrete
J 0
(-1800 1850);
PAINT MONO (-1800 1850);
DISPLAY INVISIBLE (-1800 1850);
FORCEPROP 1 LAST PATH I83
J 0
(-1750 2000);
DISPLAY 0.978723 (-1750 2000);
PAINT WHITE (-1750 2000);
DISPLAY INVISIBLE (-1750 2000);
FORCEPROP 0 LAST ROOM PVDDQ_KLM
J 0
(-1750 2050);
DISPLAY 1.021277 (-1750 2050);
PAINT ORANGE (-1750 2050);
DISPLAY INVISIBLE (-1750 2050);
FORCEPROP 0 LAST SEC 1
J 0
(-1750 2000);
DISPLAY 0.680851 (-1750 2000);
PAINT MONO (-1750 2000);
DISPLAY INVISIBLE (-1750 2000);
FORCEPROP 2 LAST SEC_TYPE 0603V
J 0
(-1750 2050);
DISPLAY 1.021277 (-1750 2050);
PAINT ORANGE (-1750 2050);
DISPLAY INVISIBLE (-1750 2050);
FORCEADD CAP_A..1
(-2200 1850);
FORCEPROP 1 LAST PACK_TYPE 0603V
J 0
(-2150 1650);
DISPLAY 0.617021 (-2150 1650);
PAINT SKYBLUE (-2150 1650);
FORCEPROP 1 LAST PART_NUMBER E15431-004
J 0
(-2150 1700);
DISPLAY 0.617021 (-2150 1700);
PAINT BLUE (-2150 1700);
FORCEPROP 1 LAST MATERIAL X6S
J 0
(-2150 1750);
DISPLAY 0.617021 (-2150 1750);
PAINT SKYBLUE (-2150 1750);
FORCEPROP 1 LAST TOLERANCE 20%
J 0
(-2150 1800);
DISPLAY 0.617021 (-2150 1800);
PAINT SKYBLUE (-2150 1800);
FORCEPROP 1 LAST VALUE 22.0UF
J 0
(-2150 1900);
DISPLAY 0.617021 (-2150 1900);
PAINT SKYBLUE (-2150 1900);
FORCEPROP 1 LAST LOCATION C5G72
J 0
(-2150 1950);
DISPLAY 0.617021 (-2150 1950);
PAINT AQUA (-2150 1950);
FORCEPROP 1 LASTPIN (-2200 1750) $PN 2
J 0
(-2190 1730);
DISPLAY 0.787234 (-2190 1730);
PAINT ORANGE (-2190 1730);
FORCEPROP 1 LASTPIN (-2200 1950) $PN 1
J 0
(-2190 1930);
DISPLAY 0.787234 (-2190 1930);
PAINT ORANGE (-2190 1930);
FORCEPROP 1 LAST VOLTAGE 4V
J 0
(-2150 1850);
DISPLAY 0.617021 (-2150 1850);
PAINT SKYBLUE (-2150 1850);
FORCEPROP 0 LAST GROUP PWR_MLCC_CAP
J 0
(-2151 1545);
DISPLAY 0.638298 (-2151 1545);
PAINT BROWN (-2151 1545);
DISPLAY BOTH (-2151 1545);
FORCEPROP 0 LAST BOM_DS NOPOP
J 0
(-2144 1602);
DISPLAY 0.638298 (-2144 1602);
PAINT BROWN (-2144 1602);
DISPLAY BOTH (-2144 1602);
FORCEPROP 2 LAST SEC_TYPE 0603V
J 0
(-2150 2050);
DISPLAY 1.021277 (-2150 2050);
PAINT ORANGE (-2150 2050);
DISPLAY INVISIBLE (-2150 2050);
FORCEPROP 0 LAST SEC 1
J 0
(-2150 2000);
DISPLAY 0.680851 (-2150 2000);
PAINT MONO (-2150 2000);
DISPLAY INVISIBLE (-2150 2000);
FORCEPROP 0 LAST ROOM PVDDQ_KLM
J 0
(-2150 2050);
DISPLAY 1.021277 (-2150 2050);
PAINT ORANGE (-2150 2050);
DISPLAY INVISIBLE (-2150 2050);
FORCEPROP 1 LAST PATH I84
J 0
(-2150 2000);
DISPLAY 0.978723 (-2150 2000);
PAINT WHITE (-2150 2000);
DISPLAY INVISIBLE (-2150 2000);
FORCEPROP 2 LAST CDS_LIB dev_discrete
J 0
(-2200 1850);
PAINT MONO (-2200 1850);
DISPLAY INVISIBLE (-2200 1850);
FORCEADD CAP_A..1
(-2600 1850);
FORCEPROP 1 LAST VALUE 22.0UF
J 0
(-2550 1900);
DISPLAY 0.617021 (-2550 1900);
PAINT SKYBLUE (-2550 1900);
FORCEPROP 1 LAST VOLTAGE 4V
J 0
(-2550 1850);
DISPLAY 0.617021 (-2550 1850);
PAINT SKYBLUE (-2550 1850);
FORCEPROP 1 LAST MATERIAL X6S
J 0
(-2550 1750);
DISPLAY 0.617021 (-2550 1750);
PAINT SKYBLUE (-2550 1750);
FORCEPROP 1 LAST TOLERANCE 20%
J 0
(-2550 1800);
DISPLAY 0.617021 (-2550 1800);
PAINT SKYBLUE (-2550 1800);
FORCEPROP 1 LASTPIN (-2600 1750) $PN 2
J 0
(-2590 1730);
DISPLAY 0.787234 (-2590 1730);
PAINT ORANGE (-2590 1730);
FORCEPROP 1 LASTPIN (-2600 1950) $PN 1
J 0
(-2590 1930);
DISPLAY 0.787234 (-2590 1930);
PAINT ORANGE (-2590 1930);
FORCEPROP 1 LAST PART_NUMBER E15431-004
J 0
(-2550 1700);
DISPLAY 0.617021 (-2550 1700);
PAINT BLUE (-2550 1700);
FORCEPROP 1 LAST PACK_TYPE 0603V
J 0
(-2550 1650);
DISPLAY 0.617021 (-2550 1650);
PAINT SKYBLUE (-2550 1650);
FORCEPROP 1 LAST LOCATION C5G71
J 0
(-2550 1950);
DISPLAY 0.617021 (-2550 1950);
PAINT AQUA (-2550 1950);
FORCEPROP 0 LAST GROUP PWR_MLCC_CAP
J 0
(-2551 1495);
DISPLAY 0.638298 (-2551 1495);
PAINT BROWN (-2551 1495);
DISPLAY BOTH (-2551 1495);
FORCEPROP 0 LAST BOM_DS NOPOP
J 0
(-2544 1602);
DISPLAY 0.638298 (-2544 1602);
PAINT BROWN (-2544 1602);
DISPLAY BOTH (-2544 1602);
FORCEPROP 2 LAST CDS_LIB dev_discrete
J 0
(-2600 1850);
PAINT MONO (-2600 1850);
DISPLAY INVISIBLE (-2600 1850);
FORCEPROP 1 LAST PATH I85
J 0
(-2550 2000);
DISPLAY 0.978723 (-2550 2000);
PAINT WHITE (-2550 2000);
DISPLAY INVISIBLE (-2550 2000);
FORCEPROP 0 LAST ROOM PVDDQ_KLM
J 0
(-2550 2050);
DISPLAY 1.021277 (-2550 2050);
PAINT ORANGE (-2550 2050);
DISPLAY INVISIBLE (-2550 2050);
FORCEPROP 0 LAST SEC 1
J 0
(-2550 2000);
DISPLAY 0.680851 (-2550 2000);
PAINT MONO (-2550 2000);
DISPLAY INVISIBLE (-2550 2000);
FORCEPROP 2 LAST SEC_TYPE 0603V
J 0
(-2550 2050);
DISPLAY 1.021277 (-2550 2050);
PAINT ORANGE (-2550 2050);
DISPLAY INVISIBLE (-2550 2050);
FORCEADD CAP_A..1
(-3000 1850);
FORCEPROP 1 LAST LOCATION C5G70
J 0
(-2950 1950);
DISPLAY 0.617021 (-2950 1950);
PAINT AQUA (-2950 1950);
FORCEPROP 1 LASTPIN (-3000 1950) $PN 1
J 0
(-2990 1930);
DISPLAY 0.787234 (-2990 1930);
PAINT ORANGE (-2990 1930);
FORCEPROP 1 LASTPIN (-3000 1750) $PN 2
J 0
(-2990 1730);
DISPLAY 0.787234 (-2990 1730);
PAINT ORANGE (-2990 1730);
FORCEPROP 1 LAST VALUE 22.0UF
J 0
(-2950 1900);
DISPLAY 0.617021 (-2950 1900);
PAINT SKYBLUE (-2950 1900);
FORCEPROP 1 LAST PART_NUMBER E15431-004
J 0
(-2950 1700);
DISPLAY 0.617021 (-2950 1700);
PAINT BLUE (-2950 1700);
FORCEPROP 1 LAST TOLERANCE 20%
J 0
(-2950 1800);
DISPLAY 0.617021 (-2950 1800);
PAINT SKYBLUE (-2950 1800);
FORCEPROP 1 LAST MATERIAL X6S
J 0
(-2950 1750);
DISPLAY 0.617021 (-2950 1750);
PAINT SKYBLUE (-2950 1750);
FORCEPROP 1 LAST PACK_TYPE 0603V
J 0
(-2950 1650);
DISPLAY 0.617021 (-2950 1650);
PAINT SKYBLUE (-2950 1650);
FORCEPROP 0 LAST GROUP PWR_MLCC_CAP
J 0
(-2951 1570);
DISPLAY 0.638298 (-2951 1570);
PAINT BROWN (-2951 1570);
DISPLAY BOTH (-2951 1570);
FORCEPROP 1 LAST VOLTAGE 4V
J 0
(-2950 1850);
DISPLAY 0.617021 (-2950 1850);
PAINT SKYBLUE (-2950 1850);
FORCEPROP 0 LAST BOM_DS NOPOP
J 0
(-2944 1602);
DISPLAY 0.638298 (-2944 1602);
PAINT BROWN (-2944 1602);
DISPLAY BOTH (-2944 1602);
FORCEPROP 2 LAST SEC_TYPE 0603V
J 0
(-2950 2050);
DISPLAY 1.021277 (-2950 2050);
PAINT ORANGE (-2950 2050);
DISPLAY INVISIBLE (-2950 2050);
FORCEPROP 0 LAST SEC 1
J 0
(-2950 2000);
DISPLAY 0.680851 (-2950 2000);
PAINT MONO (-2950 2000);
DISPLAY INVISIBLE (-2950 2000);
FORCEPROP 2 LAST CDS_LIB dev_discrete
J 0
(-3000 1850);
PAINT MONO (-3000 1850);
DISPLAY INVISIBLE (-3000 1850);
FORCEPROP 1 LAST PATH I86
J 0
(-2950 2000);
DISPLAY 0.978723 (-2950 2000);
PAINT WHITE (-2950 2000);
DISPLAY INVISIBLE (-2950 2000);
FORCEPROP 0 LAST ROOM PVDDQ_KLM
J 0
(-2950 2050);
DISPLAY 1.021277 (-2950 2050);
PAINT ORANGE (-2950 2050);
DISPLAY INVISIBLE (-2950 2050);
FORCEADD CAP_A..1
(-3400 1850);
FORCEPROP 1 LAST MATERIAL X6S
J 0
(-3350 1750);
DISPLAY 0.617021 (-3350 1750);
PAINT SKYBLUE (-3350 1750);
FORCEPROP 1 LAST TOLERANCE 20%
J 0
(-3350 1800);
DISPLAY 0.617021 (-3350 1800);
PAINT SKYBLUE (-3350 1800);
FORCEPROP 1 LASTPIN (-3400 1950) $PN 1
J 0
(-3390 1930);
DISPLAY 0.787234 (-3390 1930);
PAINT ORANGE (-3390 1930);
FORCEPROP 0 LAST GROUP PWR_MLCC_CAP
J 0
(-3351 1495);
DISPLAY 0.638298 (-3351 1495);
PAINT BROWN (-3351 1495);
DISPLAY BOTH (-3351 1495);
FORCEPROP 1 LAST PACK_TYPE 0603V
J 0
(-3350 1650);
DISPLAY 0.617021 (-3350 1650);
PAINT SKYBLUE (-3350 1650);
FORCEPROP 1 LAST PART_NUMBER E15431-004
J 0
(-3350 1700);
DISPLAY 0.617021 (-3350 1700);
PAINT BLUE (-3350 1700);
FORCEPROP 1 LASTPIN (-3400 1750) $PN 2
J 0
(-3390 1730);
DISPLAY 0.787234 (-3390 1730);
PAINT ORANGE (-3390 1730);
FORCEPROP 1 LAST VOLTAGE 4V
J 0
(-3350 1850);
DISPLAY 0.617021 (-3350 1850);
PAINT SKYBLUE (-3350 1850);
FORCEPROP 1 LAST VALUE 22.0UF
J 0
(-3350 1900);
DISPLAY 0.617021 (-3350 1900);
PAINT SKYBLUE (-3350 1900);
FORCEPROP 1 LAST LOCATION C5G69
J 0
(-3350 1950);
DISPLAY 0.617021 (-3350 1950);
PAINT AQUA (-3350 1950);
FORCEPROP 0 LAST BOM_DS NOPOP
J 0
(-3344 1602);
DISPLAY 0.638298 (-3344 1602);
PAINT BROWN (-3344 1602);
DISPLAY BOTH (-3344 1602);
FORCEPROP 0 LAST ROOM PVDDQ_KLM
J 0
(-3350 2050);
DISPLAY 1.021277 (-3350 2050);
PAINT ORANGE (-3350 2050);
DISPLAY INVISIBLE (-3350 2050);
FORCEPROP 1 LAST PATH I87
J 0
(-3350 2000);
DISPLAY 0.978723 (-3350 2000);
PAINT WHITE (-3350 2000);
DISPLAY INVISIBLE (-3350 2000);
FORCEPROP 2 LAST CDS_LIB dev_discrete
J 0
(-3400 1850);
PAINT MONO (-3400 1850);
DISPLAY INVISIBLE (-3400 1850);
FORCEPROP 0 LAST SEC 1
J 0
(-3350 2000);
DISPLAY 0.680851 (-3350 2000);
PAINT MONO (-3350 2000);
DISPLAY INVISIBLE (-3350 2000);
FORCEPROP 2 LAST SEC_TYPE 0603V
J 0
(-3350 2050);
DISPLAY 1.021277 (-3350 2050);
PAINT ORANGE (-3350 2050);
DISPLAY INVISIBLE (-3350 2050);
FORCEADD CAP_A..1
(-3800 1850);
FORCEPROP 1 LAST MATERIAL X6S
J 0
(-3750 1750);
DISPLAY 0.617021 (-3750 1750);
PAINT SKYBLUE (-3750 1750);
FORCEPROP 1 LAST PACK_TYPE 0603V
J 0
(-3750 1650);
DISPLAY 0.617021 (-3750 1650);
PAINT SKYBLUE (-3750 1650);
FORCEPROP 1 LASTPIN (-3800 1750) $PN 2
J 0
(-3790 1730);
DISPLAY 0.787234 (-3790 1730);
PAINT ORANGE (-3790 1730);
FORCEPROP 1 LAST PART_NUMBER E15431-004
J 0
(-3750 1700);
DISPLAY 0.617021 (-3750 1700);
PAINT BLUE (-3750 1700);
FORCEPROP 1 LAST LOCATION C5G68
J 0
(-3750 1950);
DISPLAY 0.617021 (-3750 1950);
PAINT AQUA (-3750 1950);
FORCEPROP 1 LAST VOLTAGE 4V
J 0
(-3750 1850);
DISPLAY 0.617021 (-3750 1850);
PAINT SKYBLUE (-3750 1850);
FORCEPROP 1 LAST TOLERANCE 20%
J 0
(-3750 1800);
DISPLAY 0.617021 (-3750 1800);
PAINT SKYBLUE (-3750 1800);
FORCEPROP 1 LAST VALUE 22.0UF
J 0
(-3750 1900);
DISPLAY 0.617021 (-3750 1900);
PAINT SKYBLUE (-3750 1900);
FORCEPROP 1 LASTPIN (-3800 1950) $PN 1
J 0
(-3790 1930);
DISPLAY 0.787234 (-3790 1930);
PAINT ORANGE (-3790 1930);
FORCEPROP 0 LAST GROUP PWR_MLCC_CAP
J 0
(-3751 1545);
DISPLAY 0.638298 (-3751 1545);
PAINT BROWN (-3751 1545);
DISPLAY BOTH (-3751 1545);
FORCEPROP 0 LAST BOM_DS NOPOP
J 0
(-3744 1602);
DISPLAY 0.638298 (-3744 1602);
PAINT BROWN (-3744 1602);
DISPLAY BOTH (-3744 1602);
FORCEPROP 2 LAST SEC_TYPE 0603V
J 0
(-3750 2050);
DISPLAY 1.021277 (-3750 2050);
PAINT ORANGE (-3750 2050);
DISPLAY INVISIBLE (-3750 2050);
FORCEPROP 0 LAST SEC 1
J 0
(-3750 2000);
DISPLAY 0.680851 (-3750 2000);
PAINT MONO (-3750 2000);
DISPLAY INVISIBLE (-3750 2000);
FORCEPROP 2 LAST CDS_LIB dev_discrete
J 0
(-3800 1850);
PAINT MONO (-3800 1850);
DISPLAY INVISIBLE (-3800 1850);
FORCEPROP 1 LAST PATH I88
J 0
(-3750 2000);
DISPLAY 0.978723 (-3750 2000);
PAINT WHITE (-3750 2000);
DISPLAY INVISIBLE (-3750 2000);
FORCEPROP 0 LAST ROOM PVDDQ_KLM
J 0
(-3750 2050);
DISPLAY 1.021277 (-3750 2050);
PAINT ORANGE (-3750 2050);
DISPLAY INVISIBLE (-3750 2050);
FORCEADD CAP..1
(-3800 3775);
FORCEPROP 1 LAST LOCATION C5G77
J 0
(-3750 3875);
DISPLAY 0.617021 (-3750 3875);
PAINT AQUA (-3750 3875);
FORCEPROP 1 LASTPIN (-3800 3875) $PN 1
J 0
(-3790 3855);
DISPLAY 0.787234 (-3790 3855);
PAINT ORANGE (-3790 3855);
FORCEPROP 1 LAST VOLTAGE 4V
J 0
(-3750 3775);
DISPLAY 0.638298 (-3750 3775);
PAINT SKYBLUE (-3750 3775);
FORCEPROP 1 LAST VALUE 47UF
J 0
(-3750 3825);
DISPLAY 0.617021 (-3750 3825);
PAINT SKYBLUE (-3750 3825);
FORCEPROP 1 LAST TOLERANCE 20%
J 0
(-3750 3725);
DISPLAY 0.617021 (-3750 3725);
PAINT SKYBLUE (-3750 3725);
FORCEPROP 1 LAST MATERIAL X6S
J 0
(-3750 3675);
DISPLAY 0.617021 (-3750 3675);
PAINT SKYBLUE (-3750 3675);
FORCEPROP 1 LASTPIN (-3800 3675) $PN 2
J 0
(-3790 3655);
DISPLAY 0.787234 (-3790 3655);
PAINT ORANGE (-3790 3655);
FORCEPROP 1 LAST PACK_TYPE 0805
J 0
(-3750 3625);
DISPLAY 0.617021 (-3750 3625);
PAINT SKYBLUE (-3750 3625);
FORCEPROP 1 LAST PART_NUMBER C95333-006
J 0
(-3750 3575);
DISPLAY 0.617021 (-3750 3575);
PAINT BLUE (-3750 3575);
FORCEPROP 0 LAST POP NOPOP
J 0
(-3744 3527);
DISPLAY 0.638298 (-3744 3527);
PAINT RED (-3744 3527);
FORCEPROP 0 LAST GROUP PWR_MLCC_CAP
J 0
(-3769 3487);
DISPLAY 0.638298 (-3769 3487);
PAINT BROWN (-3769 3487);
DISPLAY BOTH (-3769 3487);
FORCEPROP 2 LAST CDS_LIB mstr_discrete
J 0
(-3800 3775);
PAINT MONO (-3800 3775);
DISPLAY INVISIBLE (-3800 3775);
FORCEPROP 1 LAST PATH I89
J 0
(-3750 3925);
DISPLAY 0.978723 (-3750 3925);
PAINT WHITE (-3750 3925);
DISPLAY INVISIBLE (-3750 3925);
FORCEPROP 2 LAST ROOM PVCCIN_CPU0_DECAP_VR
J 0
(-3750 3925);
DISPLAY 1.021277 (-3750 3925);
PAINT ORANGE (-3750 3925);
DISPLAY INVISIBLE (-3750 3925);
FORCEPROP 2 LAST BOM_COST PROC_SOCKET
J 0
(-3750 3975);
DISPLAY 1.021277 (-3750 3975);
PAINT ORANGE (-3750 3975);
DISPLAY INVISIBLE (-3750 3975);
FORCEPROP 0 LAST SEC 1
J 0
(-3750 3925);
DISPLAY 0.680851 (-3750 3925);
PAINT MONO (-3750 3925);
DISPLAY INVISIBLE (-3750 3925);
FORCEPROP 2 LAST SEC_TYPE 0805
J 0
(-3750 3975);
DISPLAY 1.021277 (-3750 3975);
PAINT ORANGE (-3750 3975);
DISPLAY INVISIBLE (-3750 3975);
FORCEADD PVDDQ_ABC..1
(-7750 3125);
FORCEPROP 3 LASTPIN (-7750 3075) SIG_NAME PVDDQ_ABC\g
J 0
(-7740 3085);
DISPLAY 0.659574 (-7740 3085);
PAINT MONO (-7740 3085);
DISPLAY INVISIBLE (-7740 3085);
FORCEPROP 1 LAST HDL_POWER PVDDQ_ABC
J 1
(-7750 3175);
DISPLAY 0.872340 (-7750 3175);
PAINT GREEN (-7750 3175);
DISPLAY INVISIBLE (-7750 3175);
FORCEPROP 1 LAST BODY_TYPE PLUMBING
J 0
(-7795 3082);
DISPLAY 0.340426 (-7795 3082);
PAINT GREEN (-7795 3082);
DISPLAY INVISIBLE (-7795 3082);
FORCEPROP 1 LAST VOLTAGE 1.2V
J 0
(-7795 3082);
DISPLAY 0.340426 (-7795 3082);
PAINT GREEN (-7795 3082);
DISPLAY INVISIBLE (-7795 3082);
FORCEPROP 2 LAST BOM_COST PROC_SOCKET 
J 0
(-7750 3225);
DISPLAY 1.446809 (-7750 3225);
PAINT MONO (-7750 3225);
DISPLAY INVISIBLE (-7750 3225);
FORCEPROP 2 LAST ROOM VDDQ_ABC_PWR_VR
J 0
(-7750 3225);
DISPLAY 1.936170 (-7750 3225);
PAINT ORANGE (-7750 3225);
DISPLAY INVISIBLE (-7750 3225);
FORCEPROP 2 LAST CDS_LIB mstr_symbols
J 0
(-7750 3125);
PAINT MONO (-7750 3125);
DISPLAY INVISIBLE (-7750 3125);
FORCEPROP 1 LAST PATH I9
J 0
(-7700 3150);
DISPLAY 0.872340 (-7700 3150);
PAINT AQUA (-7700 3150);
DISPLAY INVISIBLE (-7700 3150);
FORCEADD CAP..1
(-7350 3775);
FORCEPROP 1 LAST PART_NUMBER C95333-006
J 0
(-7300 3575);
DISPLAY 0.617021 (-7300 3575);
PAINT BLUE (-7300 3575);
FORCEPROP 1 LAST VALUE 47UF
J 0
(-7300 3825);
DISPLAY 0.617021 (-7300 3825);
PAINT SKYBLUE (-7300 3825);
FORCEPROP 1 LAST VOLTAGE 4V
J 0
(-7300 3775);
DISPLAY 0.638298 (-7300 3775);
PAINT SKYBLUE (-7300 3775);
FORCEPROP 0 LAST POP NOPOP
J 0
(-7291 3511);
DISPLAY 0.638298 (-7291 3511);
PAINT RED (-7291 3511);
FORCEPROP 1 LASTPIN (-7350 3675) $PN 2
J 0
(-7340 3655);
DISPLAY 0.787234 (-7340 3655);
PAINT ORANGE (-7340 3655);
FORCEPROP 1 LASTPIN (-7350 3875) $PN 1
J 0
(-7340 3855);
DISPLAY 0.787234 (-7340 3855);
PAINT ORANGE (-7340 3855);
FORCEPROP 1 LAST LOCATION C5G22
J 0
(-7300 3875);
DISPLAY 0.617021 (-7300 3875);
PAINT AQUA (-7300 3875);
FORCEPROP 1 LAST MATERIAL X6S
J 0
(-7300 3675);
DISPLAY 0.617021 (-7300 3675);
PAINT SKYBLUE (-7300 3675);
FORCEPROP 1 LAST PACK_TYPE 0805
J 0
(-7300 3625);
DISPLAY 0.617021 (-7300 3625);
PAINT SKYBLUE (-7300 3625);
FORCEPROP 1 LAST TOLERANCE 20%
J 0
(-7300 3725);
DISPLAY 0.617021 (-7300 3725);
PAINT SKYBLUE (-7300 3725);
FORCEPROP 0 LAST GROUP PWR_MLCC_CAP
J 0
(-7294 3387);
DISPLAY 0.638298 (-7294 3387);
PAINT BROWN (-7294 3387);
DISPLAY BOTH (-7294 3387);
FORCEPROP 2 LAST SEC_TYPE 0805
J 0
(-7300 3975);
DISPLAY 1.021277 (-7300 3975);
PAINT ORANGE (-7300 3975);
DISPLAY INVISIBLE (-7300 3975);
FORCEPROP 0 LAST SEC 1
J 0
(-7300 3925);
DISPLAY 0.680851 (-7300 3925);
PAINT MONO (-7300 3925);
DISPLAY INVISIBLE (-7300 3925);
FORCEPROP 2 LAST ROOM PVCCIN_CPU0_DECAP_VR
J 0
(-7300 3925);
DISPLAY 1.021277 (-7300 3925);
PAINT ORANGE (-7300 3925);
DISPLAY INVISIBLE (-7300 3925);
FORCEPROP 2 LAST BOM_COST PROC_SOCKET
J 0
(-7300 3975);
DISPLAY 1.021277 (-7300 3975);
PAINT ORANGE (-7300 3975);
DISPLAY INVISIBLE (-7300 3975);
FORCEPROP 1 LAST PATH I90
J 0
(-7300 3925);
DISPLAY 0.978723 (-7300 3925);
PAINT WHITE (-7300 3925);
DISPLAY INVISIBLE (-7300 3925);
FORCEPROP 2 LAST CDS_LIB mstr_discrete
J 0
(-7350 3775);
PAINT MONO (-7350 3775);
DISPLAY INVISIBLE (-7350 3775);
FORCEADD CAP..1
(-3400 3775);
FORCEPROP 0 LAST POP NOPOP
J 0
(-3344 3527);
DISPLAY 0.638298 (-3344 3527);
PAINT RED (-3344 3527);
FORCEPROP 1 LAST VOLTAGE 4V
J 0
(-3350 3775);
DISPLAY 0.638298 (-3350 3775);
PAINT SKYBLUE (-3350 3775);
FORCEPROP 1 LAST TOLERANCE 20%
J 0
(-3350 3725);
DISPLAY 0.617021 (-3350 3725);
PAINT SKYBLUE (-3350 3725);
FORCEPROP 1 LASTPIN (-3400 3675) $PN 2
J 0
(-3390 3655);
DISPLAY 0.787234 (-3390 3655);
PAINT ORANGE (-3390 3655);
FORCEPROP 1 LASTPIN (-3400 3875) $PN 1
J 0
(-3390 3855);
DISPLAY 0.787234 (-3390 3855);
PAINT ORANGE (-3390 3855);
FORCEPROP 1 LAST PACK_TYPE 0805
J 0
(-3350 3625);
DISPLAY 0.617021 (-3350 3625);
PAINT SKYBLUE (-3350 3625);
FORCEPROP 1 LAST VALUE 47UF
J 0
(-3350 3825);
DISPLAY 0.617021 (-3350 3825);
PAINT SKYBLUE (-3350 3825);
FORCEPROP 1 LAST PART_NUMBER C95333-006
J 0
(-3350 3575);
DISPLAY 0.617021 (-3350 3575);
PAINT BLUE (-3350 3575);
FORCEPROP 0 LAST GROUP PWR_MLCC_CAP
J 0
(-3344 3437);
DISPLAY 0.638298 (-3344 3437);
PAINT BROWN (-3344 3437);
DISPLAY BOTH (-3344 3437);
FORCEPROP 1 LAST LOCATION C5G78
J 0
(-3350 3875);
DISPLAY 0.617021 (-3350 3875);
PAINT AQUA (-3350 3875);
FORCEPROP 1 LAST MATERIAL X6S
J 0
(-3350 3675);
DISPLAY 0.617021 (-3350 3675);
PAINT SKYBLUE (-3350 3675);
FORCEPROP 2 LAST BOM_COST PROC_SOCKET
J 0
(-3350 3975);
DISPLAY 1.021277 (-3350 3975);
PAINT ORANGE (-3350 3975);
DISPLAY INVISIBLE (-3350 3975);
FORCEPROP 2 LAST ROOM PVCCIN_CPU0_DECAP_VR
J 0
(-3350 3925);
DISPLAY 1.021277 (-3350 3925);
PAINT ORANGE (-3350 3925);
DISPLAY INVISIBLE (-3350 3925);
FORCEPROP 1 LAST PATH I91
J 0
(-3350 3925);
DISPLAY 0.978723 (-3350 3925);
PAINT WHITE (-3350 3925);
DISPLAY INVISIBLE (-3350 3925);
FORCEPROP 2 LAST CDS_LIB mstr_discrete
J 0
(-3400 3775);
PAINT MONO (-3400 3775);
DISPLAY INVISIBLE (-3400 3775);
FORCEPROP 0 LAST SEC 1
J 0
(-3350 3925);
DISPLAY 0.680851 (-3350 3925);
PAINT MONO (-3350 3925);
DISPLAY INVISIBLE (-3350 3925);
FORCEPROP 2 LAST SEC_TYPE 0805
J 0
(-3350 3975);
DISPLAY 1.021277 (-3350 3975);
PAINT ORANGE (-3350 3975);
DISPLAY INVISIBLE (-3350 3975);
FORCEADD CAP..1
(-7750 3775);
FORCEPROP 0 LAST GROUP PWR_MLCC_CAP
J 0
(-7694 3437);
DISPLAY 0.638298 (-7694 3437);
PAINT BROWN (-7694 3437);
DISPLAY BOTH (-7694 3437);
FORCEPROP 0 LAST POP NOPOP
J 0
(-7697 3498);
DISPLAY 0.638298 (-7697 3498);
PAINT RED (-7697 3498);
FORCEPROP 1 LAST PART_NUMBER C95333-006
J 0
(-7700 3575);
DISPLAY 0.617021 (-7700 3575);
PAINT BLUE (-7700 3575);
FORCEPROP 1 LAST VOLTAGE 4V
J 0
(-7700 3775);
DISPLAY 0.638298 (-7700 3775);
PAINT SKYBLUE (-7700 3775);
FORCEPROP 1 LASTPIN (-7750 3675) $PN 2
J 0
(-7740 3655);
DISPLAY 0.787234 (-7740 3655);
PAINT ORANGE (-7740 3655);
FORCEPROP 1 LASTPIN (-7750 3875) $PN 1
J 0
(-7740 3855);
DISPLAY 0.787234 (-7740 3855);
PAINT ORANGE (-7740 3855);
FORCEPROP 1 LAST TOLERANCE 20%
J 0
(-7700 3725);
DISPLAY 0.617021 (-7700 3725);
PAINT SKYBLUE (-7700 3725);
FORCEPROP 1 LAST VALUE 47UF
J 0
(-7700 3825);
DISPLAY 0.617021 (-7700 3825);
PAINT SKYBLUE (-7700 3825);
FORCEPROP 1 LAST LOCATION C5G21
J 0
(-7700 3875);
DISPLAY 0.617021 (-7700 3875);
PAINT AQUA (-7700 3875);
FORCEPROP 1 LAST MATERIAL X6S
J 0
(-7700 3675);
DISPLAY 0.617021 (-7700 3675);
PAINT SKYBLUE (-7700 3675);
FORCEPROP 1 LAST PACK_TYPE 0805
J 0
(-7700 3625);
DISPLAY 0.617021 (-7700 3625);
PAINT SKYBLUE (-7700 3625);
FORCEPROP 2 LAST SEC_TYPE 0805
J 0
(-7700 3975);
DISPLAY 1.021277 (-7700 3975);
PAINT ORANGE (-7700 3975);
DISPLAY INVISIBLE (-7700 3975);
FORCEPROP 0 LAST SEC 1
J 0
(-7700 3925);
DISPLAY 0.680851 (-7700 3925);
PAINT MONO (-7700 3925);
DISPLAY INVISIBLE (-7700 3925);
FORCEPROP 2 LAST CDS_LIB mstr_discrete
J 0
(-7750 3775);
PAINT MONO (-7750 3775);
DISPLAY INVISIBLE (-7750 3775);
FORCEPROP 1 LAST PATH I92
J 0
(-7700 3925);
DISPLAY 0.978723 (-7700 3925);
PAINT WHITE (-7700 3925);
DISPLAY INVISIBLE (-7700 3925);
FORCEPROP 2 LAST ROOM PVCCIN_CPU0_DECAP_VR
J 0
(-7700 3925);
DISPLAY 1.021277 (-7700 3925);
PAINT ORANGE (-7700 3925);
DISPLAY INVISIBLE (-7700 3925);
FORCEPROP 2 LAST BOM_COST PROC_SOCKET
J 0
(-7700 3975);
DISPLAY 1.021277 (-7700 3975);
PAINT ORANGE (-7700 3975);
DISPLAY INVISIBLE (-7700 3975);
FORCEADD INTEL_CORP_BPAGE..1
(0 0);
FORCEPROP 1 LAST CDS_CON_LAST_MODIFIED Fri Jun 16 17:49:27 2017
J 0
(-1425 325);
PAINT ORANGE (-1425 325);
DISPLAY INVISIBLE (-1425 325);
FORCEPROP 1 LAST CUSTOM_TXT_CDS <CURRENT_DESIGN_SHEET> OF <TOTAL_DESIGN_SHEETS>
J 0
(-500 25);
PAINT ORANGE (-500 25);
FORCEPROP 1 LAST CUSTOM_TXT_CDS <CON_LAST_MODIFIED>
J 0
(-4000 100);
PAINT ORANGE (-4000 100);
FORCEPROP 2 LAST CUSTOM_TXT_CDS <XR_PAGE_TITLE>
J 0
(-7890 5250);
DISPLAY 0.638298 (-7890 5250);
PAINT PINK (-7890 5250);
DISPLAY INVISIBLE (-7890 5250);
FORCEPROP 1 LAST SCH_TITLE ADD DIMM CAP FOR SINGLE SIDE MB (1/2)
J 0
(-7950 50);
DISPLAY 2.468085 (-7950 50);
PAINT ORANGE (-7950 50);
FORCEPROP 1 LAST COMMENT_BODY TRUE
J 0
(12 12);
DISPLAY 0.468085 (12 12);
PAINT GREEN (12 12);
DISPLAY INVISIBLE (12 12);
FORCEPROP 2 LAST CDS_LIB mstr_symbols
J 0
(0 0);
PAINT MONO (0 0);
DISPLAY INVISIBLE (0 0);
FORCEPROP 2 LAST PAGE_BORDER TRUE
J 0
(-7890 5250);
DISPLAY 0.638298 (-7890 5250);
PAINT PINK (-7890 5250);
DISPLAY INVISIBLE (-7890 5250);
FORCEPROP 2 LAST CDS_XR_PAGE_TITLE CR-242 : @BASEBOARD_FAB2_LIB.BASEBOARD_FAB2(SCH_1):PAGE242
J 0
(-7890 5250);
DISPLAY 0.638298 (-7890 5250);
PAINT PINK (-7890 5250);
DISPLAY INVISIBLE (-7890 5250);
WIRE 16 -1 (-7750 1550)(-7750 1500);
WIRE 16 -1 (-7750 1550)(-7350 1550);
WIRE 16 -1 (-7750 1750)(-7750 1550);
WIRE 16 -1 (-7350 1550)(-6950 1550);
WIRE 16 -1 (-7350 1750)(-7350 1550);
WIRE 16 -1 (-6950 1550)(-6550 1550);
WIRE 16 -1 (-6950 1750)(-6950 1550);
WIRE 16 -1 (-6550 1550)(-6150 1550);
WIRE 16 -1 (-6550 1750)(-6550 1550);
WIRE 16 -1 (-6150 1550)(-5750 1550);
WIRE 16 -1 (-6150 1750)(-6150 1550);
WIRE 16 -1 (-5750 1550)(-5350 1550);
WIRE 16 -1 (-5750 1750)(-5750 1550);
WIRE 16 -1 (-5350 1550)(-4950 1550);
WIRE 16 -1 (-5350 1750)(-5350 1550);
WIRE 16 -1 (-4550 1550)(-4950 1550);
WIRE 16 -1 (-4950 1750)(-4950 1550);
WIRE 16 -1 (-4550 1750)(-4550 1550);
WIRE 16 -1 (-7750 3425)(-7750 3475);
WIRE 16 -1 (-7750 3475)(-7350 3475);
WIRE 16 -1 (-7750 3675)(-7750 3475);
WIRE 16 -1 (-7350 3475)(-7350 3675);
WIRE 16 -1 (-3800 1550)(-3800 1500);
WIRE 16 -1 (-3800 1550)(-3400 1550);
WIRE 16 -1 (-3800 1750)(-3800 1550);
WIRE 16 -1 (-3400 1550)(-3000 1550);
WIRE 16 -1 (-3400 1750)(-3400 1550);
WIRE 16 -1 (-3000 1550)(-2600 1550);
WIRE 16 -1 (-3000 1750)(-3000 1550);
WIRE 16 -1 (-2600 1550)(-2200 1550);
WIRE 16 -1 (-2600 1750)(-2600 1550);
WIRE 16 -1 (-2200 1550)(-1800 1550);
WIRE 16 -1 (-2200 1750)(-2200 1550);
WIRE 16 -1 (-1800 1550)(-1400 1550);
WIRE 16 -1 (-1800 1750)(-1800 1550);
WIRE 16 -1 (-1400 1550)(-1000 1550);
WIRE 16 -1 (-1400 1750)(-1400 1550);
WIRE 16 -1 (-600 1550)(-1000 1550);
WIRE 16 -1 (-1000 1750)(-1000 1550);
WIRE 16 -1 (-600 1750)(-600 1550);
WIRE 16 -1 (-3800 2050)(-3800 2100);
WIRE 16 -1 (-3800 2050)(-3400 2050);
WIRE 16 -1 (-3800 1950)(-3800 2050);
WIRE 16 -1 (-3400 2050)(-3000 2050);
WIRE 16 -1 (-3400 1950)(-3400 2050);
WIRE 16 -1 (-3000 2050)(-2600 2050);
WIRE 16 -1 (-3000 1950)(-3000 2050);
WIRE 16 -1 (-2600 2050)(-2200 2050);
WIRE 16 -1 (-2600 1950)(-2600 2050);
WIRE 16 -1 (-2200 2050)(-1800 2050);
WIRE 16 -1 (-2200 1950)(-2200 2050);
WIRE 16 -1 (-1800 2050)(-1400 2050);
WIRE 16 -1 (-1800 1950)(-1800 2050);
WIRE 16 -1 (-1400 2050)(-1000 2050);
WIRE 16 -1 (-1400 1950)(-1400 2050);
WIRE 16 -1 (-1000 2050)(-600 2050);
WIRE 16 -1 (-1000 1950)(-1000 2050);
WIRE 16 -1 (-600 1950)(-600 2050);
WIRE 16 -1 (-7750 2050)(-7750 2100);
WIRE 16 -1 (-7750 2050)(-7350 2050);
WIRE 16 -1 (-7750 1950)(-7750 2050);
WIRE 16 -1 (-7350 2050)(-6950 2050);
WIRE 16 -1 (-7350 1950)(-7350 2050);
WIRE 16 -1 (-6950 2050)(-6550 2050);
WIRE 16 -1 (-6950 1950)(-6950 2050);
WIRE 16 -1 (-6550 2050)(-6150 2050);
WIRE 16 -1 (-6550 1950)(-6550 2050);
WIRE 16 -1 (-6150 2050)(-5750 2050);
WIRE 16 -1 (-6150 1950)(-6150 2050);
WIRE 16 -1 (-5750 2050)(-5350 2050);
WIRE 16 -1 (-5750 1950)(-5750 2050);
WIRE 16 -1 (-5350 2050)(-4950 2050);
WIRE 16 -1 (-5350 1950)(-5350 2050);
WIRE 16 -1 (-4950 2050)(-4550 2050);
WIRE 16 -1 (-4950 1950)(-4950 2050);
WIRE 16 -1 (-4550 1950)(-4550 2050);
WIRE 16 -1 (-3800 2500)(-3800 2450);
WIRE 16 -1 (-3800 2500)(-3400 2500);
WIRE 16 -1 (-3800 2700)(-3800 2500);
WIRE 16 -1 (-3400 2500)(-3000 2500);
WIRE 16 -1 (-3400 2700)(-3400 2500);
WIRE 16 -1 (-3000 2500)(-2600 2500);
WIRE 16 -1 (-3000 2700)(-3000 2500);
WIRE 16 -1 (-2600 2500)(-2200 2500);
WIRE 16 -1 (-2600 2700)(-2600 2500);
WIRE 16 -1 (-2200 2500)(-1800 2500);
WIRE 16 -1 (-2200 2700)(-2200 2500);
WIRE 16 -1 (-1800 2500)(-1400 2500);
WIRE 16 -1 (-1800 2700)(-1800 2500);
WIRE 16 -1 (-1400 2500)(-1000 2500);
WIRE 16 -1 (-1400 2700)(-1400 2500);
WIRE 16 -1 (-600 2500)(-1000 2500);
WIRE 16 -1 (-1000 2700)(-1000 2500);
WIRE 16 -1 (-600 2700)(-600 2500);
WIRE 16 -1 (-3800 3000)(-3800 3050);
WIRE 16 -1 (-3800 3000)(-3400 3000);
WIRE 16 -1 (-3800 2900)(-3800 3000);
WIRE 16 -1 (-3400 3000)(-3000 3000);
WIRE 16 -1 (-3400 2900)(-3400 3000);
WIRE 16 -1 (-3000 3000)(-2600 3000);
WIRE 16 -1 (-3000 2900)(-3000 3000);
WIRE 16 -1 (-2600 3000)(-2200 3000);
WIRE 16 -1 (-2600 2900)(-2600 3000);
WIRE 16 -1 (-2200 3000)(-1800 3000);
WIRE 16 -1 (-2200 2900)(-2200 3000);
WIRE 16 -1 (-1800 3000)(-1400 3000);
WIRE 16 -1 (-1800 2900)(-1800 3000);
WIRE 16 -1 (-1400 3000)(-1000 3000);
WIRE 16 -1 (-1400 2900)(-1400 3000);
WIRE 16 -1 (-1000 3000)(-600 3000);
WIRE 16 -1 (-1000 2900)(-1000 3000);
WIRE 16 -1 (-600 2900)(-600 3000);
WIRE 16 -1 (-3800 3400)(-3800 3450);
WIRE 16 -1 (-3800 3450)(-3400 3450);
WIRE 16 -1 (-3800 3675)(-3800 3450);
WIRE 16 -1 (-3400 3450)(-3400 3675);
WIRE 16 -1 (-3800 3950)(-3800 4000);
WIRE 16 -1 (-3400 3950)(-3800 3950);
WIRE 16 -1 (-3800 3950)(-3800 3875);
WIRE 16 -1 (-3400 3875)(-3400 3950);
WIRE 16 -1 (-7750 2500)(-7750 2450);
WIRE 16 -1 (-7750 2500)(-7350 2500);
WIRE 16 -1 (-7750 2700)(-7750 2500);
WIRE 16 -1 (-7350 2500)(-6950 2500);
WIRE 16 -1 (-7350 2700)(-7350 2500);
WIRE 16 -1 (-6950 2500)(-6550 2500);
WIRE 16 -1 (-6950 2700)(-6950 2500);
WIRE 16 -1 (-6550 2500)(-6150 2500);
WIRE 16 -1 (-6550 2700)(-6550 2500);
WIRE 16 -1 (-6150 2500)(-5750 2500);
WIRE 16 -1 (-6150 2700)(-6150 2500);
WIRE 16 -1 (-5750 2500)(-5350 2500);
WIRE 16 -1 (-5750 2700)(-5750 2500);
WIRE 16 -1 (-5350 2500)(-4950 2500);
WIRE 16 -1 (-5350 2700)(-5350 2500);
WIRE 16 -1 (-4550 2500)(-4950 2500);
WIRE 16 -1 (-4950 2700)(-4950 2500);
WIRE 16 -1 (-4550 2700)(-4550 2500);
WIRE 16 -1 (-7750 3000)(-7750 3075);
WIRE 16 -1 (-7750 3000)(-7350 3000);
WIRE 16 -1 (-7750 2900)(-7750 3000);
WIRE 16 -1 (-7350 3000)(-6950 3000);
WIRE 16 -1 (-7350 2900)(-7350 3000);
WIRE 16 -1 (-6950 3000)(-6550 3000);
WIRE 16 -1 (-6950 2900)(-6950 3000);
WIRE 16 -1 (-6550 3000)(-6150 3000);
WIRE 16 -1 (-6550 2900)(-6550 3000);
WIRE 16 -1 (-6150 3000)(-5750 3000);
WIRE 16 -1 (-6150 2900)(-6150 3000);
WIRE 16 -1 (-5750 3000)(-5350 3000);
WIRE 16 -1 (-5750 2900)(-5750 3000);
WIRE 16 -1 (-5350 3000)(-4950 3000);
WIRE 16 -1 (-5350 2900)(-5350 3000);
WIRE 16 -1 (-4950 3000)(-4550 3000);
WIRE 16 -1 (-4950 2900)(-4950 3000);
WIRE 16 -1 (-4550 2900)(-4550 3000);
WIRE 16 -1 (-7750 4025)(-7750 3975);
WIRE 16 -1 (-7350 3975)(-7750 3975);
WIRE 16 -1 (-7750 3975)(-7750 3875);
WIRE 16 -1 (-7350 3875)(-7350 3975);
WIRE 3 682 (-7900 3300)(-6700 3300);
WIRE 3 682 (-7900 4250)(-7900 3300);
WIRE 3 682 (-6700 3300)(-6700 4250);
WIRE 3 682 (-6700 4250)(-7900 4250);
WIRE 3 682 (-4050 3300)(-2725 3300);
WIRE 3 682 (-4050 4200)(-4050 3300);
WIRE 3 682 (-2725 3300)(-2725 4200);
WIRE 3 682 (-2725 4200)(-4050 4200);
DOT 1 (-7350 2500);
DOT 1 (-1000 3000);
DOT 1 (-1000 2500);
DOT 1 (-1000 2050);
DOT 1 (-1400 3000);
DOT 1 (-1400 2050);
DOT 1 (-1400 2500);
DOT 1 (-1800 3000);
DOT 1 (-1800 2050);
DOT 1 (-1800 2500);
DOT 1 (-1000 1550);
DOT 1 (-1400 1550);
DOT 1 (-1800 1550);
DOT 1 (-2200 3000);
DOT 1 (-2200 2500);
DOT 1 (-2200 2050);
DOT 1 (-2600 3000);
DOT 1 (-3000 3000);
DOT 1 (-2600 2500);
DOT 1 (-2600 2050);
DOT 1 (-3000 2500);
DOT 1 (-3000 2050);
DOT 1 (-3800 3950);
DOT 1 (-3800 3450);
DOT 1 (-3400 3000);
DOT 1 (-3400 2050);
DOT 1 (-3800 3000);
DOT 1 (-3800 2500);
DOT 1 (-3800 2050);
DOT 1 (-2200 1550);
DOT 1 (-2600 1550);
DOT 1 (-3000 1550);
DOT 1 (-3400 1550);
DOT 1 (-3800 1550);
DOT 1 (-4950 3000);
DOT 1 (-4950 2050);
DOT 1 (-4950 2500);
DOT 1 (-5350 3000);
DOT 1 (-5350 2050);
DOT 1 (-5350 2500);
DOT 1 (-5750 3000);
DOT 1 (-5750 2500);
DOT 1 (-5750 2050);
DOT 1 (-4950 1550);
DOT 1 (-5350 1550);
DOT 1 (-5750 1550);
DOT 1 (-6150 3000);
DOT 1 (-6550 3000);
DOT 1 (-6150 2500);
DOT 1 (-6150 2050);
DOT 1 (-6550 2500);
DOT 1 (-6550 2050);
DOT 1 (-6950 3000);
DOT 1 (-6950 2050);
DOT 1 (-6950 2500);
DOT 1 (-7750 3975);
DOT 1 (-7750 3475);
DOT 1 (-7350 3000);
DOT 1 (-7350 2050);
DOT 1 (-7750 3000);
DOT 1 (-7750 2500);
DOT 1 (-7750 2050);
DOT 1 (-6150 1550);
DOT 1 (-6550 1550);
DOT 1 (-6950 1550);
DOT 1 (-7350 1550);
DOT 1 (-7750 1550);
DOT 1 (-3400 2500);
FORCENOTE
TP FAB1 ADD CAP ON DIMM BOTTOM SIDE 1116
(-4955 622) 0;
DISPLAY LEFT (-4955 622);
DISPLAY 1.021277 (-4955 622);
PAINT RED (-4955 622);
FORCENOTE
TP FAB3-DVT NOPOP 20161220
(-7900 3250) 0;
DISPLAY LEFT (-7900 3250);
DISPLAY 0.638298 (-7900 3250);
PAINT RED (-7900 3250);
FORCENOTE
TP FAB3-DVT NOPOP 20161220
(-4050 3250) 0;
DISPLAY LEFT (-4050 3250);
DISPLAY 0.638298 (-4050 3250);
PAINT RED (-4050 3250);
QUIT
